%FSTAX23Y23*%
%MOIN*%
%SFA1B1*%

%IPPOS*%
%ADD10C,0.009840*%
%ADD11C,0.023620*%
%ADD12C,0.003940*%
%ADD13C,0.010000*%
%ADD14C,0.007870*%
%ADD15C,0.015750*%
%ADD16C,0.015750*%
%ADD17C,0.006000*%
%ADD18C,0.004720*%
%ADD19C,0.008000*%
%ADD20C,0.007000*%
%ADD21C,0.005000*%
%ADD22C,0.005910*%
%ADD23C,0.007990*%
%ADD24C,0.009000*%
%ADD25R,0.025000X0.010000*%
%LNgrandmaster-1*%
%LPD*%
G36*
X02221Y03944D02*
X02221Y03944D01*
Y03943*
X02221Y03943*
X02221Y03943*
X02221Y03943*
X02221Y03942*
X02221Y03942*
X02221Y03941*
X02221Y03941*
X0222Y03941*
X0222Y0394*
X0222Y0394*
Y0394*
X0222Y0394*
X0222Y0394*
X0222Y0394*
X0222Y0394*
X0222Y0394*
X0222Y03939*
X0222Y03939*
X0222Y03939*
X0222Y03939*
X02219Y03939*
X02219Y03939*
X02219Y03938*
X02219Y03938*
X02219Y03938*
X02218Y03938*
X02218Y03938*
X02218Y03938*
X02218Y03938*
X02218Y03938*
X02218Y03938*
X02218Y03938*
X02218Y03938*
X02218Y03938*
X02217Y03938*
X02217Y03937*
X02217Y03937*
X02217Y03937*
X02216Y03937*
X02216Y03937*
X02216Y03937*
X02216Y03937*
X02216*
X02216*
X02215Y03937*
X02215*
X02215Y03937*
X02215Y03937*
X02215Y03937*
X02214Y03937*
X02214Y03937*
X02214Y03937*
X02214Y03938*
X02213Y03938*
X02213Y03938*
X02213Y03938*
X02212Y03938*
X02212Y03938*
X02212Y03939*
X02212Y03939*
X02212Y03939*
X02212Y03939*
X02212Y03939*
X02212Y03939*
X02212Y03939*
X02211Y03939*
X02211Y0394*
X02211Y0394*
X02211Y0394*
X02211Y03941*
X02211Y03941*
X02211Y03942*
X0221Y03942*
X0221Y03943*
Y03943*
X0221Y03943*
X0221Y03942*
X0221Y03942*
X0221Y03942*
X0221Y03942*
X0221Y03942*
X0221Y03942*
X0221Y03941*
X0221Y03941*
X02209Y03941*
X02209Y03941*
X02209Y03941*
X02209Y03941*
X02209Y03941*
X02209Y03941*
X02209Y03941*
X02209Y0394*
X02209Y0394*
X02209Y0394*
X02208Y0394*
X02208Y0394*
X02208Y0394*
X02208Y0394*
X02207Y03939*
X02207Y03939*
X02202Y03936*
Y03939*
X02206Y03941*
X02206Y03941*
X02206Y03941*
X02206Y03941*
X02206Y03942*
X02206Y03942*
X02206Y03942*
X02206Y03942*
X02207Y03942*
X02207Y03942*
X02208Y03943*
X02208Y03943*
X02208Y03943*
X02208Y03943*
X02208Y03943*
X02208Y03943*
X02208Y03943*
X02208Y03943*
X02209Y03943*
X02209Y03944*
X02209Y03944*
X02209Y03944*
X02209Y03944*
X0221Y03944*
X0221Y03944*
X0221Y03945*
X0221Y03945*
X0221Y03945*
X0221Y03945*
X0221Y03945*
X0221Y03945*
X0221Y03946*
Y03946*
X0221Y03946*
X0221Y03946*
X0221Y03946*
X0221Y03946*
X0221Y03946*
X0221Y03947*
Y0395*
X02202*
Y03952*
X02221*
Y03944*
G37*
G36*
X02216Y03932D02*
X02216Y03932D01*
X02216Y03932*
X02216Y03932*
X02216Y03932*
X02216Y03932*
X02217Y03931*
X02217Y03931*
X02217Y03931*
X02217Y03931*
X02217Y0393*
X02218Y03929*
X02218Y03929*
X02218Y03929*
X02218Y03929*
X02218Y03929*
X02219Y03929*
X02219Y03929*
X02219Y03928*
X02219Y03928*
X02219Y03928*
X02219Y03928*
X0222Y03928*
X0222Y03927*
X0222Y03927*
X02221Y03927*
X02221Y03927*
Y03925*
X02202*
Y03928*
X02217*
X02217Y03928*
X02217Y03928*
X02217Y03928*
X02217Y03928*
X02216Y03928*
X02216Y03928*
X02216Y03928*
X02216Y03928*
X02216Y03928*
X02216Y03929*
X02216Y03929*
X02216Y03929*
X02215Y03929*
X02215Y03929*
X02215Y0393*
X02215Y0393*
X02215Y0393*
X02215Y0393*
X02215Y0393*
X02215Y0393*
X02215Y0393*
X02215Y03931*
X02215Y03931*
X02214Y03931*
X02214Y03932*
X02214Y03932*
X02214Y03932*
X02216*
X02216Y03932*
G37*
G36*
X02207Y03917D02*
X02207D01*
X02207Y03917*
X02207Y03917*
X02207Y03917*
X02207Y03917*
X02206Y03917*
X02206Y03917*
X02206Y03917*
X02205Y03916*
X02205Y03916*
X02205Y03916*
X02205Y03916*
X02204Y03916*
X02204Y03916*
X02204Y03916*
X02204Y03916*
X02204Y03916*
X02204Y03915*
X02204Y03915*
X02204Y03915*
X02204Y03915*
X02204Y03915*
X02204Y03915*
X02204Y03915*
X02204Y03914*
X02203Y03914*
X02203Y03914*
X02203Y03914*
X02203Y03914*
X02203Y03913*
Y03913*
X02203Y03913*
Y03913*
X02203Y03913*
X02203Y03913*
X02203Y03912*
X02203Y03912*
X02204Y03912*
X02204Y03912*
X02204Y03912*
X02204Y03911*
X02204Y03911*
X02204Y03911*
X02204Y03911*
X02204Y0391*
X02204Y0391*
X02205Y0391*
X02205Y0391*
X02205Y0391*
X02205Y0391*
X02205Y0391*
X02205Y0391*
X02205Y0391*
X02205Y0391*
X02206Y0391*
X02206Y0391*
X02206Y03909*
X02206Y03909*
X02207Y03909*
X02207Y03909*
X02207Y03909*
X02207*
X02207*
X02207*
X02208Y03909*
X02208Y03909*
X02208Y03909*
X02208Y03909*
X02208Y03909*
X02208Y03909*
X02209Y0391*
X02209Y0391*
X02209Y0391*
X02209Y0391*
X0221Y0391*
X0221Y0391*
X0221Y0391*
X0221Y0391*
X0221Y0391*
X0221Y0391*
X0221Y03911*
X0221Y03911*
X0221Y03911*
X0221Y03911*
X0221Y03911*
X02211Y03911*
X02211Y03911*
X02211Y03912*
X02211Y03912*
X02211Y03912*
X02211Y03912*
X02211Y03913*
X02211Y03913*
Y03913*
X02211Y03913*
X02211Y03913*
X02211Y03914*
X02211Y03914*
X02211Y03914*
X02211Y03915*
X02213Y03914*
Y03914*
X02213Y03914*
Y03914*
X02213Y03914*
Y03914*
X02213Y03914*
X02213Y03914*
X02213Y03914*
X02213Y03913*
X02213Y03913*
X02213Y03913*
X02213Y03913*
X02213Y03912*
X02213Y03912*
X02213Y03912*
X02213Y03912*
X02214Y03911*
X02214Y03911*
X02214Y03911*
X02214Y03911*
X02214Y03911*
X02214Y03911*
X02214Y03911*
X02214Y03911*
X02214Y03911*
X02214Y03911*
X02214Y03911*
X02215Y0391*
X02215Y0391*
X02215Y0391*
X02215Y0391*
X02216Y0391*
X02216Y0391*
X02216*
X02216*
X02216*
X02216Y0391*
X02216Y0391*
X02216Y0391*
X02217Y0391*
X02217Y0391*
X02217Y0391*
X02217Y0391*
X02217Y03911*
X02218Y03911*
X02218Y03911*
X02218Y03911*
X02218Y03911*
X02218Y03911*
X02218Y03911*
X02218Y03911*
X02218Y03911*
X02218Y03911*
X02218Y03911*
X02218Y03912*
X02219Y03912*
X02219Y03912*
X02219Y03912*
X02219Y03912*
X02219Y03912*
X02219Y03913*
X02219Y03913*
X02219Y03913*
X02219Y03913*
Y03913*
X02219Y03914*
X02219Y03914*
X02219Y03914*
X02219Y03914*
X02219Y03914*
X02219Y03914*
X02219Y03915*
X02219Y03915*
X02218Y03915*
X02218Y03915*
X02218Y03915*
X02218Y03916*
X02218Y03916*
X02218Y03916*
X02218Y03916*
X02218Y03916*
X02218Y03916*
X02218Y03916*
X02218Y03916*
X02217Y03916*
X02217Y03916*
X02217Y03916*
X02217Y03916*
X02217Y03916*
X02216Y03917*
X02216Y03917*
X02216Y03917*
X02216Y03917*
X02216Y03919*
X02216*
X02216*
X02216Y03919*
X02216Y03919*
X02216Y03919*
X02217Y03919*
X02217Y03919*
X02217Y03919*
X02217Y03919*
X02218Y03919*
X02218Y03918*
X02218Y03918*
X02218Y03918*
X02219Y03918*
X02219Y03918*
X02219Y03917*
X0222Y03917*
X0222Y03917*
X0222Y03917*
X0222Y03917*
X0222Y03917*
X0222Y03917*
X0222Y03917*
X0222Y03916*
X0222Y03916*
X0222Y03916*
X0222Y03916*
X02221Y03915*
X02221Y03915*
X02221Y03915*
X02221Y03914*
X02221Y03914*
X02221Y03913*
Y03913*
X02221Y03913*
Y03913*
X02221Y03913*
X02221Y03913*
X02221Y03912*
X02221Y03912*
X02221Y03912*
X02221Y03911*
X02221Y03911*
X0222Y03911*
X0222Y03911*
X0222Y0391*
X0222Y0391*
X0222Y0391*
X0222Y0391*
X0222Y0391*
X0222Y0391*
X0222Y0391*
X0222Y0391*
X0222Y0391*
X02219Y03909*
X02219Y03909*
X02219Y03909*
X02219Y03909*
X02218Y03908*
X02218Y03908*
X02218Y03908*
X02218Y03908*
X02218Y03908*
X02218Y03908*
X02218Y03908*
X02218Y03908*
X02218Y03908*
X02217Y03908*
X02217Y03908*
X02217Y03908*
X02216Y03908*
X02216Y03908*
X02216Y03908*
X02216*
X02216*
X02216*
X02216Y03908*
X02216*
X02215Y03908*
X02215Y03908*
X02215Y03908*
X02215Y03908*
X02214Y03908*
X02214Y03908*
X02214Y03908*
X02214Y03908*
X02214Y03908*
X02214Y03908*
X02214Y03908*
X02214Y03908*
X02213Y03909*
X02213Y03909*
X02213Y03909*
X02213Y03909*
X02213Y03909*
X02213Y03909*
X02213Y03909*
X02213Y03909*
X02213Y0391*
X02212Y0391*
X02212Y0391*
X02212Y0391*
X02212Y0391*
Y0391*
X02212Y0391*
X02212Y0391*
X02212Y0391*
X02212Y0391*
X02212Y0391*
X02212Y0391*
X02212Y03909*
X02212Y03909*
X02211Y03909*
X02211Y03909*
X02211Y03909*
X02211Y03908*
X02211Y03908*
X02211Y03908*
X0221Y03908*
X0221Y03908*
X0221Y03908*
X0221Y03908*
X0221Y03908*
X0221Y03908*
X0221Y03907*
X0221Y03907*
X0221Y03907*
X02209Y03907*
X02209Y03907*
X02209Y03907*
X02209Y03907*
X02208Y03907*
X02208Y03907*
X02208Y03907*
X02207Y03907*
X02207*
X02207*
X02207Y03907*
X02207Y03907*
X02207Y03907*
X02206Y03907*
X02206Y03907*
X02206Y03907*
X02206Y03907*
X02205Y03907*
X02205Y03907*
X02204Y03908*
X02204Y03908*
X02204Y03908*
X02203Y03908*
X02203Y03909*
X02203Y03909*
X02203Y03909*
X02203Y03909*
X02203Y03909*
X02203Y03909*
X02203Y03909*
X02202Y0391*
X02202Y0391*
X02202Y0391*
X02202Y03911*
X02202Y03911*
X02202Y03911*
X02202Y03912*
X02201Y03912*
X02201Y03913*
X02201Y03913*
Y03913*
X02201Y03914*
X02201Y03914*
X02201Y03914*
X02201Y03914*
X02201Y03914*
X02202Y03915*
X02202Y03915*
X02202Y03915*
X02202Y03916*
X02202Y03916*
X02202Y03916*
X02202Y03917*
X02203Y03917*
X02203Y03917*
X02203Y03917*
X02203Y03918*
X02203Y03918*
X02203Y03918*
X02203Y03918*
X02203Y03918*
X02204Y03918*
X02204Y03918*
X02204Y03918*
X02204Y03919*
X02205Y03919*
X02205Y03919*
X02206Y03919*
X02206Y03919*
X02206Y03919*
X02207Y03919*
X02207Y03917*
G37*
G36*
X02159Y03943D02*
X02159Y03942D01*
Y03942*
X02159Y03942*
X02159Y03942*
X02159Y03941*
X02159Y03941*
X02159Y03941*
X02158Y0394*
X02158Y0394*
X02158Y0394*
X02158Y03939*
X02158Y03939*
Y03939*
X02158Y03939*
X02158Y03939*
X02158Y03939*
X02158Y03939*
X02158Y03939*
X02158Y03938*
X02158Y03938*
X02158Y03938*
X02157Y03938*
X02157Y03938*
X02157Y03938*
X02157Y03937*
X02157Y03937*
X02157Y03937*
X02156Y03937*
X02156Y03937*
X02156Y03937*
X02156Y03937*
X02156Y03937*
X02156Y03937*
X02156Y03937*
X02156Y03937*
X02155Y03936*
X02155Y03936*
X02155Y03936*
X02155Y03936*
X02155Y03936*
X02154Y03936*
X02154Y03936*
X02154Y03936*
X02153Y03936*
X02153*
X02153*
X02153Y03936*
X02153*
X02153Y03936*
X02153Y03936*
X02152Y03936*
X02152Y03936*
X02152Y03936*
X02152Y03936*
X02151Y03937*
X02151Y03937*
X02151Y03937*
X02151Y03937*
X0215Y03937*
X0215Y03937*
X0215Y03937*
X0215Y03937*
X0215Y03938*
X0215Y03938*
X0215Y03938*
X0215Y03938*
X02149Y03938*
X02149Y03938*
X02149Y03939*
X02149Y03939*
X02149Y03939*
X02149Y0394*
X02149Y0394*
X02148Y03941*
X02148Y03941*
X02148Y03941*
Y03941*
X02148Y03941*
X02148Y03941*
X02148Y03941*
X02148Y03941*
X02148Y03941*
X02148Y03941*
X02148Y03941*
X02148Y0394*
X02147Y0394*
X02147Y0394*
X02147Y0394*
X02147Y0394*
X02147Y0394*
X02147Y0394*
X02147Y0394*
X02147Y0394*
X02147Y03939*
X02147Y03939*
X02146Y03939*
X02146Y03939*
X02146Y03939*
X02146Y03939*
X02146Y03938*
X02145Y03938*
X02145Y03938*
X0214Y03935*
Y03938*
X02144Y0394*
X02144Y0394*
X02144Y0394*
X02144Y0394*
X02144Y0394*
X02144Y03941*
X02144Y03941*
X02144Y03941*
X02144Y03941*
X02145Y03941*
X02145Y03941*
X02146Y03942*
X02146Y03942*
X02146Y03942*
X02146Y03942*
X02146Y03942*
X02146Y03942*
X02146Y03942*
X02146Y03942*
X02147Y03942*
X02147Y03943*
X02147Y03943*
X02147Y03943*
X02147Y03943*
X02147Y03943*
X02147Y03943*
X02148Y03944*
X02148Y03944*
X02148Y03944*
X02148Y03944*
X02148Y03944*
X02148Y03944*
Y03945*
X02148Y03945*
X02148Y03945*
X02148Y03945*
X02148Y03945*
X02148Y03945*
X02148Y03946*
Y03949*
X0214*
Y03951*
X02159*
Y03943*
G37*
G36*
X02154Y03931D02*
X02154Y03931D01*
X02154Y03931*
X02154Y03931*
X02154Y03931*
X02154Y03931*
X02154Y0393*
X02155Y0393*
X02155Y0393*
X02155Y0393*
X02155Y03929*
X02156Y03928*
X02156Y03928*
X02156Y03928*
X02156Y03928*
X02156Y03928*
X02156Y03928*
X02156Y03927*
X02157Y03927*
X02157Y03927*
X02157Y03927*
X02157Y03927*
X02157Y03927*
X02158Y03926*
X02158Y03926*
X02158Y03926*
X02159Y03926*
Y03924*
X0214*
Y03927*
X02154*
X02154Y03927*
X02154Y03927*
X02154Y03927*
X02154Y03927*
X02154Y03927*
X02154Y03927*
X02154Y03927*
X02154Y03927*
X02154Y03927*
X02154Y03928*
X02154Y03928*
X02153Y03928*
X02153Y03928*
X02153Y03928*
X02153Y03929*
X02153Y03929*
X02153Y03929*
X02153Y03929*
X02153Y03929*
X02153Y03929*
X02153Y03929*
X02152Y03929*
X02152Y0393*
X02152Y0393*
X02152Y0393*
X02152Y03931*
X02152Y03931*
X02154*
X02154Y03931*
G37*
G36*
X0214Y03919D02*
X0214Y03919D01*
X0214Y03918*
X02141Y03918*
X02141Y03918*
X02141Y03918*
X02141*
X02141Y03918*
X02141Y03918*
X02141Y03918*
X02141Y03918*
X02142Y03918*
X02142Y03918*
X02142Y03918*
X02142Y03918*
X02142Y03918*
X02143Y03917*
X02143Y03917*
X02144Y03917*
X02144Y03917*
X02144Y03917*
X02144Y03917*
X02144Y03917*
X02144Y03916*
X02144Y03916*
X02144Y03916*
X02145Y03916*
X02145Y03916*
X02145Y03916*
X02145Y03915*
X02145Y03915*
X02146Y03915*
X02146Y03914*
X02146Y03914*
X02147Y03914*
X02147Y03914*
X02147Y03914*
X02147Y03914*
X02147Y03914*
X02147Y03913*
X02147Y03913*
X02147Y03913*
X02147Y03913*
X02147Y03913*
X02148Y03912*
X02148Y03912*
X02148Y03912*
X02149Y03911*
X02149Y03911*
X02149Y03911*
X0215Y0391*
X0215Y0391*
X0215Y0391*
X02151Y03909*
X02151Y03909*
X02151Y03909*
X02151Y03909*
X02151Y03909*
X02151Y03909*
X02151Y03909*
X02151Y03909*
X02152Y03909*
X02152Y03909*
X02152Y03909*
X02152Y03909*
X02153Y03908*
X02153Y03908*
X02153Y03908*
X02153Y03908*
X02153*
X02154*
X02154*
X02154Y03908*
X02154Y03908*
X02154Y03908*
X02154Y03908*
X02154Y03908*
X02154Y03909*
X02155Y03909*
X02155Y03909*
X02155Y03909*
X02155Y03909*
X02155Y03909*
X02156Y03909*
X02156Y03909*
X02156Y03909*
X02156Y03909*
X02156Y03909*
X02156Y0391*
X02156Y0391*
X02156Y0391*
X02156Y0391*
X02156Y0391*
X02156Y0391*
X02156Y0391*
X02157Y03911*
X02157Y03911*
X02157Y03911*
X02157Y03911*
X02157Y03912*
X02157Y03912*
Y03912*
X02157Y03912*
X02157Y03912*
X02157Y03913*
X02157Y03913*
X02157Y03913*
X02157Y03913*
X02157Y03913*
X02156Y03914*
X02156Y03914*
X02156Y03914*
X02156Y03914*
X02156Y03914*
X02156Y03915*
X02156Y03915*
X02156Y03915*
X02156Y03915*
X02156Y03915*
X02155Y03915*
X02155Y03915*
X02155Y03915*
X02155Y03915*
X02155Y03915*
X02155Y03915*
X02154Y03915*
X02154Y03916*
X02154Y03916*
X02154Y03916*
X02153Y03916*
X02153Y03916*
X02153Y03918*
X02153*
X02153*
X02153Y03918*
X02153*
X02153Y03918*
X02154Y03918*
X02154Y03918*
X02154Y03918*
X02154Y03918*
X02155Y03918*
X02155Y03918*
X02155Y03918*
X02156Y03917*
X02156Y03917*
X02156Y03917*
X02157Y03917*
X02157Y03917*
X02157Y03916*
X02157Y03916*
X02157Y03916*
X02157Y03916*
X02157Y03916*
X02158Y03916*
X02158Y03916*
X02158Y03915*
X02158Y03915*
X02158Y03915*
X02158Y03914*
X02158Y03914*
X02158Y03914*
X02159Y03913*
X02159Y03913*
X02159Y03912*
X02159Y03912*
Y03912*
X02159Y03912*
X02159Y03911*
X02159Y03911*
X02159Y03911*
X02159Y03911*
X02159Y0391*
X02158Y0391*
X02158Y0391*
X02158Y03909*
X02158Y03909*
X02158Y03909*
X02158Y03908*
X02157Y03908*
X02157Y03908*
X02157Y03908*
X02157Y03907*
X02157Y03907*
X02157Y03907*
X02157Y03907*
X02157Y03907*
X02156Y03907*
X02156Y03907*
X02156Y03907*
X02156Y03906*
X02155Y03906*
X02155Y03906*
X02155Y03906*
X02154Y03906*
X02154Y03906*
X02153Y03906*
X02153*
X02153*
X02153*
X02153*
X02153Y03906*
X02153Y03906*
X02153Y03906*
X02153Y03906*
X02152Y03906*
X02152Y03906*
X02152Y03906*
X02151Y03906*
X02151*
X02151Y03906*
X02151Y03906*
X02151Y03907*
X02151Y03907*
X02151Y03907*
X02151Y03907*
X0215Y03907*
X0215Y03907*
X0215Y03907*
X0215Y03907*
X02149Y03907*
X02149Y03908*
X02149Y03908*
X02149Y03908*
X02149Y03908*
X02149Y03908*
X02149Y03908*
X02149Y03908*
X02148Y03908*
X02148Y03908*
X02148Y03909*
X02148Y03909*
X02148Y03909*
X02147Y03909*
X02147Y0391*
X02147Y0391*
X02147Y0391*
X02146Y03911*
X02146Y03911*
X02145Y03912*
X02145Y03912*
X02145Y03912*
X02145Y03912*
X02145Y03912*
X02145Y03912*
X02145Y03912*
X02145Y03912*
X02144Y03913*
X02144Y03913*
X02144Y03913*
X02144Y03914*
X02143Y03914*
X02143Y03914*
X02143Y03914*
X02143Y03914*
X02143Y03914*
X02143Y03914*
X02143Y03915*
X02143Y03915*
X02142Y03915*
X02142Y03915*
X02142Y03915*
X02142Y03915*
Y03906*
X0214*
Y03919*
X0214*
X0214*
X0214*
X0214*
X0214*
X0214Y03919*
G37*
G36*
X01309Y04041D02*
X01294D01*
X01294Y04041*
X01294Y04041*
X01294Y04041*
X01294Y04041*
X01295Y04041*
X01295Y0404*
X01295Y0404*
X01295Y0404*
X01295Y0404*
X01295Y0404*
X01295Y0404*
X01295Y04039*
X01296Y04039*
X01296Y04039*
X01296Y04039*
X01296Y04039*
X01296Y04038*
X01296Y04038*
X01296Y04038*
X01296Y04038*
X01296Y04038*
X01296Y04038*
X01296Y04038*
X01297Y04037*
X01297Y04037*
X01297Y04036*
X01297Y04036*
X01295*
X01295Y04036*
X01295Y04036*
X01295Y04036*
X01295Y04036*
X01295Y04037*
X01295Y04037*
X01294Y04037*
X01294Y04037*
X01294Y04037*
X01294Y04038*
X01294Y04038*
X01293Y04039*
X01293Y0404*
X01293Y0404*
X01293Y0404*
X01293Y0404*
X01292Y0404*
X01292Y0404*
X01292Y0404*
X01292Y0404*
X01292Y0404*
X01292Y0404*
X01291Y04041*
X01291Y04041*
X01291Y04041*
X0129Y04041*
X0129Y04042*
Y04043*
X01309*
Y04041*
G37*
G36*
Y04026D02*
X01294D01*
X01294Y04026*
X01294Y04026*
X01294Y04026*
X01294Y04026*
X01295Y04026*
X01295Y04026*
X01295Y04025*
X01295Y04025*
X01295Y04025*
X01295Y04025*
X01295Y04025*
X01295Y04025*
X01296Y04024*
X01296Y04024*
X01296Y04024*
X01296Y04024*
X01296Y04024*
X01296Y04024*
X01296Y04023*
X01296Y04023*
X01296Y04023*
X01296Y04023*
X01296Y04023*
X01297Y04022*
X01297Y04022*
X01297Y04022*
X01297Y04021*
X01295*
X01295Y04021*
X01295Y04021*
X01295Y04021*
X01295Y04022*
X01295Y04022*
X01295Y04022*
X01294Y04022*
X01294Y04022*
X01294Y04023*
X01294Y04023*
X01294Y04024*
X01293Y04024*
X01293Y04025*
X01293Y04025*
X01293Y04025*
X01293Y04025*
X01292Y04025*
X01292Y04025*
X01292Y04025*
X01292Y04025*
X01292Y04025*
X01292Y04026*
X01291Y04026*
X01291Y04026*
X01291Y04026*
X0129Y04027*
X0129Y04027*
Y04028*
X01309*
Y04026*
G37*
G36*
Y04015D02*
X01305Y04012D01*
X01305Y04012*
X01305Y04012*
X01305Y04012*
X01305Y04012*
X01305Y04012*
X01305Y04012*
X01305Y04012*
X01304Y04012*
X01304Y04011*
X01303Y04011*
X01303Y04011*
X01303Y04011*
X01303Y0401*
X01303Y0401*
X01303Y0401*
X01303Y0401*
X01303Y0401*
X01302Y0401*
X01302Y0401*
X01302Y0401*
X01302Y0401*
X01302Y04009*
X01301Y04009*
X01301Y04009*
X01301Y04009*
X01301Y04009*
X01301Y04009*
X01301Y04009*
X01301Y04008*
X01301Y04008*
X01301Y04008*
Y04008*
X01301Y04008*
X01301Y04008*
X01301Y04008*
X01301Y04008*
X01301Y04007*
X01301Y04007*
Y04004*
X01309*
Y04001*
X0129*
Y0401*
X0129Y0401*
Y0401*
X0129Y04011*
X0129Y04011*
X0129Y04011*
X0129Y04011*
X0129Y04012*
X0129Y04012*
X0129Y04013*
X01291Y04013*
X01291Y04013*
X01291Y04014*
Y04014*
X01291Y04014*
X01291Y04014*
X01291Y04014*
X01291Y04014*
X01291Y04014*
X01291Y04014*
X01291Y04014*
X01291Y04014*
X01291Y04015*
X01292Y04015*
X01292Y04015*
X01292Y04015*
X01292Y04015*
X01292Y04015*
X01293Y04016*
X01293Y04016*
X01293Y04016*
X01293Y04016*
X01293Y04016*
X01293Y04016*
X01293Y04016*
X01293Y04016*
X01293Y04016*
X01294Y04016*
X01294Y04016*
X01294Y04016*
X01294Y04016*
X01295Y04016*
X01295Y04016*
X01295Y04016*
X01295Y04016*
X01295*
X01295*
X01296Y04016*
X01296*
X01296Y04016*
X01296Y04016*
X01296Y04016*
X01297Y04016*
X01297Y04016*
X01297Y04016*
X01297Y04016*
X01298Y04016*
X01298Y04016*
X01298Y04016*
X01299Y04015*
X01299Y04015*
X01299Y04015*
X01299Y04015*
X01299Y04015*
X01299Y04015*
X01299Y04015*
X01299Y04015*
X01299Y04014*
X013Y04014*
X013Y04014*
X013Y04014*
X013Y04013*
X013Y04013*
X013Y04012*
X013Y04012*
X01301Y04012*
X01301Y04011*
Y04011*
X01301Y04011*
X01301Y04011*
X01301Y04011*
X01301Y04011*
X01301Y04011*
X01301Y04012*
X01301Y04012*
X01301Y04012*
X01301Y04012*
X01302Y04013*
X01302Y04013*
X01302Y04013*
X01302Y04013*
X01302Y04013*
X01302Y04013*
X01302Y04013*
X01302Y04013*
X01302Y04013*
X01302Y04013*
X01303Y04014*
X01303Y04014*
X01303Y04014*
X01303Y04014*
X01304Y04014*
X01304Y04015*
X01309Y04018*
Y04015*
G37*
G36*
X01297Y04157D02*
X01297D01*
X01298Y04157*
X01298Y04157*
X01298Y04157*
X01299Y04157*
X01299Y04157*
X013Y04157*
X013Y04157*
X01301Y04157*
X01301Y04157*
X01302Y04157*
X01302Y04156*
X01302Y04156*
X01302Y04156*
X01302Y04156*
X01303Y04156*
X01303Y04156*
X01303Y04156*
X01303Y04156*
X01303Y04156*
X01304Y04156*
X01304Y04156*
X01304Y04155*
X01304Y04155*
X01305Y04155*
X01305Y04155*
X01305Y04155*
X01305Y04154*
X01305Y04154*
X01305Y04154*
X01305Y04154*
X01306Y04154*
X01306Y04154*
X01306Y04154*
X01306Y04154*
X01306Y04153*
X01306Y04153*
X01306Y04153*
X01306Y04153*
X01306Y04152*
X01306Y04152*
X01306Y04152*
X01306Y04151*
X01306Y04151*
Y04151*
X01306Y04151*
X01306Y0415*
X01306Y0415*
X01306Y0415*
X01306Y0415*
X01306Y04149*
X01306Y04149*
X01306Y04149*
X01306Y04148*
X01306Y04148*
X01305Y04148*
X01305Y04147*
X01305Y04147*
X01305Y04147*
X01305*
X01305Y04147*
X01304Y04147*
X01304Y04146*
X01304Y04146*
X01304Y04146*
X01304Y04146*
X01304Y04146*
X01304Y04146*
X01304Y04146*
X01304Y04146*
X01303Y04146*
X01303Y04146*
X01303Y04146*
X01303Y04146*
X01303Y04146*
X01302Y04146*
X01302Y04145*
X01302Y04145*
X01302Y04145*
X01301Y04145*
X01301Y04145*
X01301Y04145*
X013Y04145*
X013Y04145*
X01299Y04145*
X01299Y04145*
X01299Y04145*
X01298Y04145*
X01298Y04145*
X01297Y04145*
X01297*
X01297*
X01297*
X01297*
X01297*
X01297*
X01296*
X01296Y04145*
X01296*
X01296Y04145*
X01296Y04145*
X01295Y04145*
X01295Y04145*
X01294Y04145*
X01294Y04145*
X01293Y04145*
X01293Y04145*
X01292Y04145*
X01292Y04145*
X01291Y04145*
X01291Y04145*
X01291Y04145*
X01291Y04145*
X01291Y04145*
X01291Y04146*
X01291Y04146*
X0129Y04146*
X0129Y04146*
X0129Y04146*
X0129Y04146*
X01289Y04146*
X01289Y04147*
X01289Y04147*
X01289Y04147*
X01288Y04147*
X01288Y04147*
X01288Y04147*
X01288Y04148*
X01288Y04148*
X01288Y04148*
X01288Y04148*
X01288Y04148*
X01288Y04148*
X01288Y04148*
X01287Y04149*
X01287Y04149*
X01287Y04149*
X01287Y04149*
X01287Y0415*
X01287Y0415*
X01287Y04151*
X01287Y04151*
Y04151*
X01287Y04151*
Y04151*
X01287Y04151*
X01287Y04152*
X01287Y04152*
X01287Y04152*
X01287Y04153*
X01287Y04153*
X01288Y04153*
X01288Y04154*
Y04154*
X01288Y04154*
X01288Y04154*
X01288Y04154*
X01288Y04154*
X01288Y04154*
X01288Y04154*
X01288Y04154*
X01288Y04155*
X01289Y04155*
X01289Y04155*
X01289Y04155*
X01289Y04156*
X01289Y04156*
X0129Y04156*
X0129Y04156*
X0129Y04156*
X0129Y04156*
X0129Y04156*
X0129Y04156*
X0129Y04156*
X01291Y04156*
X01291Y04156*
X01291Y04156*
X01291Y04156*
X01292Y04157*
X01292Y04157*
X01292Y04157*
X01292*
X01292Y04157*
X01292Y04157*
X01293Y04157*
X01293Y04157*
X01293Y04157*
X01293Y04157*
X01293Y04157*
X01294Y04157*
X01294Y04157*
X01294Y04157*
X01295Y04157*
X01295Y04157*
X01296Y04157*
X01296Y04157*
X01297*
X01297*
X01297*
X01297*
X01297*
X01297*
X01297*
X01297Y04157*
G37*
G36*
X01306Y04136D02*
X01291D01*
X01291Y04136*
X01291Y04136*
X01291Y04136*
X01291Y04136*
X01291Y04136*
X01292Y04136*
X01292Y04136*
X01292Y04136*
X01292Y04136*
X01292Y04135*
X01292Y04135*
X01292Y04135*
X01292Y04135*
X01293Y04135*
X01293Y04134*
X01293Y04134*
X01293Y04134*
X01293Y04134*
X01293Y04134*
X01293Y04134*
X01293Y04134*
X01293Y04133*
X01293Y04133*
X01294Y04133*
X01294Y04132*
X01294Y04132*
X01294Y04132*
X01292*
X01292Y04132*
X01292Y04132*
X01292Y04132*
X01292Y04132*
X01292Y04132*
X01291Y04132*
X01291Y04133*
X01291Y04133*
X01291Y04133*
X01291Y04133*
X0129Y04134*
X0129Y04135*
X0129Y04135*
X0129Y04135*
X0129Y04135*
X01289Y04135*
X01289Y04135*
X01289Y04135*
X01289Y04136*
X01289Y04136*
X01289Y04136*
X01289Y04136*
X01288Y04136*
X01288Y04137*
X01287Y04137*
X01287Y04137*
X01287Y04137*
Y04139*
X01306*
Y04136*
G37*
G36*
Y04125D02*
X01302Y04123D01*
X01302Y04123*
X01302Y04123*
X01302Y04123*
X01302Y04122*
X01302Y04122*
X01302Y04122*
X01301Y04122*
X01301Y04122*
X01301Y04122*
X013Y04121*
X013Y04121*
X013Y04121*
X013Y04121*
X013Y04121*
X013Y04121*
X01299Y04121*
X01299Y04121*
X01299Y04121*
X01299Y0412*
X01299Y0412*
X01299Y0412*
X01298Y0412*
X01298Y0412*
X01298Y0412*
X01298Y04119*
X01298Y04119*
X01298Y04119*
X01298Y04119*
X01298Y04119*
X01298Y04119*
X01298Y04118*
Y04118*
X01298Y04118*
X01298Y04118*
X01298Y04118*
X01298Y04118*
X01298Y04118*
X01298Y04117*
Y04114*
X01306*
Y04112*
X01287*
Y0412*
X01287Y0412*
Y04121*
X01287Y04121*
X01287Y04121*
X01287Y04121*
X01287Y04122*
X01287Y04122*
X01287Y04123*
X01287Y04123*
X01287Y04123*
X01288Y04124*
X01288Y04124*
Y04124*
X01288Y04124*
X01288Y04124*
X01288Y04124*
X01288Y04124*
X01288Y04124*
X01288Y04125*
X01288Y04125*
X01288Y04125*
X01288Y04125*
X01288Y04125*
X01289Y04125*
X01289Y04126*
X01289Y04126*
X01289Y04126*
X01289Y04126*
X01289Y04126*
X01289Y04126*
X0129Y04126*
X0129Y04126*
X0129Y04126*
X0129Y04126*
X0129Y04126*
X0129Y04126*
X0129Y04127*
X01291Y04127*
X01291Y04127*
X01291Y04127*
X01291Y04127*
X01292Y04127*
X01292Y04127*
X01292Y04127*
X01292*
X01292*
X01292Y04127*
X01293*
X01293Y04127*
X01293Y04127*
X01293Y04127*
X01293Y04127*
X01294Y04127*
X01294Y04127*
X01294Y04126*
X01295Y04126*
X01295Y04126*
X01295Y04126*
X01295Y04126*
X01296Y04126*
X01296Y04125*
X01296Y04125*
X01296Y04125*
X01296Y04125*
X01296Y04125*
X01296Y04125*
X01296Y04125*
X01296Y04125*
X01297Y04124*
X01297Y04124*
X01297Y04124*
X01297Y04123*
X01297Y04123*
X01297Y04122*
X01297Y04122*
X01297Y04121*
Y04121*
X01298Y04121*
X01298Y04122*
X01298Y04122*
X01298Y04122*
X01298Y04122*
X01298Y04122*
X01298Y04122*
X01298Y04123*
X01298Y04123*
X01298Y04123*
X01298Y04123*
X01298Y04123*
X01299Y04123*
X01299Y04123*
X01299Y04123*
X01299Y04123*
X01299Y04124*
X01299Y04124*
X01299Y04124*
X013Y04124*
X013Y04124*
X013Y04124*
X013Y04125*
X013Y04125*
X01301Y04125*
X01306Y04128*
Y04125*
G37*
%LNgrandmaster-2*%
%LPC*%
G36*
X02219Y0395D02*
X02212D01*
Y03944*
X02212Y03944*
Y03944*
X02212Y03944*
X02212Y03943*
X02212Y03943*
X02213Y03943*
X02213Y03942*
X02213Y03942*
X02213Y03942*
Y03942*
X02213Y03942*
X02213Y03942*
X02213Y03942*
X02213Y03942*
X02213Y03941*
X02213Y03941*
X02213Y03941*
X02213Y03941*
X02214Y0394*
X02214Y0394*
X02214*
X02214Y0394*
X02214Y0394*
X02214Y0394*
X02214Y0394*
X02214Y0394*
X02214Y0394*
X02215Y0394*
X02215Y0394*
X02215Y0394*
X02216Y0394*
X02216*
X02216*
X02216*
X02216Y0394*
X02216Y0394*
X02216Y0394*
X02216Y0394*
X02216Y0394*
X02217Y0394*
X02217Y0394*
X02217Y0394*
X02217Y0394*
X02217Y0394*
X02217Y0394*
X02218Y03941*
X02218Y03941*
X02218Y03941*
X02218Y03941*
X02218Y03941*
X02218Y03941*
X02218Y03941*
X02218Y03941*
X02218Y03941*
X02218Y03942*
X02218Y03942*
X02218Y03942*
X02218Y03942*
X02219Y03942*
X02219Y03943*
X02219Y03943*
X02219Y03943*
X02219Y03944*
Y0395*
G37*
G36*
X02157Y03949D02*
X0215D01*
Y03943*
X0215Y03943*
Y03943*
X0215Y03943*
X0215Y03942*
X0215Y03942*
X0215Y03942*
X0215Y03941*
X0215Y03941*
X02151Y03941*
Y03941*
X02151Y03941*
X02151Y03941*
X02151Y03941*
X02151Y0394*
X02151Y0394*
X02151Y0394*
X02151Y0394*
X02151Y0394*
X02151Y03939*
X02152Y03939*
X02152*
X02152Y03939*
X02152Y03939*
X02152Y03939*
X02152Y03939*
X02152Y03939*
X02152Y03939*
X02152Y03939*
X02153Y03939*
X02153Y03939*
X02153Y03939*
X02153*
X02153*
X02154*
X02154Y03939*
X02154Y03939*
X02154Y03939*
X02154Y03939*
X02154Y03939*
X02154Y03939*
X02155Y03939*
X02155Y03939*
X02155Y03939*
X02155Y03939*
X02155Y03939*
X02155Y0394*
X02156Y0394*
X02156Y0394*
X02156Y0394*
X02156Y0394*
X02156Y0394*
X02156Y0394*
X02156Y0394*
X02156Y0394*
X02156Y0394*
X02156Y03941*
X02156Y03941*
X02156Y03941*
X02156Y03941*
X02156Y03942*
X02156Y03942*
X02157Y03942*
X02157Y03943*
Y03949*
G37*
G36*
X01295Y04014D02*
X01295D01*
X01295*
X01295*
X01295Y04014*
X01295Y04014*
X01295Y04014*
X01295Y04014*
X01295Y04014*
X01294Y04014*
X01294Y04014*
X01294Y04014*
X01294Y04013*
X01294Y04013*
X01294Y04013*
X01293Y04013*
X01293Y04013*
X01293Y04013*
X01293Y04013*
X01293Y04013*
X01293Y04013*
X01293Y04013*
X01293Y04012*
X01293Y04012*
X01293Y04012*
X01293Y04012*
X01293Y04012*
X01293Y04011*
X01292Y04011*
X01292Y04011*
X01292Y0401*
X01292Y0401*
X01292Y0401*
Y04004*
X01299*
Y04009*
X01299Y0401*
Y0401*
X01299Y0401*
X01299Y0401*
X01299Y04011*
X01298Y04011*
X01298Y04011*
X01298Y04012*
X01298Y04012*
Y04012*
X01298Y04012*
X01298Y04012*
X01298Y04012*
X01298Y04012*
X01298Y04012*
X01298Y04012*
X01298Y04013*
X01298Y04013*
X01297Y04013*
X01297Y04013*
X01297*
X01297Y04013*
X01297Y04013*
X01297Y04013*
X01297Y04013*
X01297Y04013*
X01297Y04014*
X01296Y04014*
X01296Y04014*
X01296Y04014*
X01295Y04014*
G37*
G36*
X01297Y04155D02*
X01297D01*
X01297*
X01297*
X01297*
X01297*
X01296*
X01296*
X01296Y04155*
X01296*
X01296Y04155*
X01296*
X01295Y04155*
X01295Y04155*
X01294Y04155*
X01294Y04155*
X01293Y04154*
X01293Y04154*
X01292Y04154*
X01292Y04154*
X01291Y04154*
X01291Y04154*
X01291Y04154*
X01291Y04154*
X01291Y04154*
X0129Y04154*
X0129Y04154*
X0129Y04153*
X0129Y04153*
X0129Y04153*
X0129Y04153*
X0129Y04153*
X0129Y04153*
X0129Y04153*
X01289Y04152*
X01289Y04152*
X01289Y04152*
X01289Y04152*
X01289Y04151*
X01289Y04151*
X01289Y04151*
Y04151*
X01289Y04151*
X01289Y04151*
X01289Y0415*
X01289Y0415*
X01289Y0415*
X01289Y0415*
X01289Y0415*
X01289Y0415*
X01289Y04149*
X0129Y04149*
X0129Y04149*
X0129Y04149*
X0129Y04148*
X0129Y04148*
X0129Y04148*
X0129Y04148*
X01291Y04148*
X01291Y04148*
X01291Y04148*
X01291Y04148*
X01291Y04148*
X01292Y04148*
X01292Y04148*
X01292Y04148*
X01292Y04148*
X01293Y04147*
X01293Y04147*
X01293Y04147*
X01293Y04147*
X01294Y04147*
X01294Y04147*
X01294Y04147*
X01295Y04147*
X01295Y04147*
X01296Y04147*
X01296Y04147*
X01296Y04147*
X01297*
X01297*
X01297*
X01297*
X01297*
X01297*
X01297Y04147*
X01297*
X01298*
X01298Y04147*
X01298*
X01298Y04147*
X01299Y04147*
X01299Y04147*
X013Y04147*
X013Y04147*
X01301Y04147*
X01301Y04148*
X01302Y04148*
X01302Y04148*
X01303Y04148*
X01303Y04148*
X01303Y04148*
X01303Y04148*
X01303Y04148*
X01303Y04148*
X01303Y04148*
X01303Y04148*
X01303Y04148*
X01303Y04149*
X01304Y04149*
X01304Y04149*
X01304Y04149*
X01304Y04149*
X01304Y0415*
X01304Y0415*
X01304Y0415*
X01304Y0415*
X01305Y04151*
X01305Y04151*
Y04151*
X01305Y04151*
X01305Y04151*
X01305Y04151*
X01304Y04151*
X01304Y04152*
X01304Y04152*
X01304Y04152*
X01304Y04152*
X01304Y04152*
X01304Y04153*
X01304Y04153*
X01304Y04153*
X01303Y04153*
X01303Y04154*
X01303Y04154*
X01303Y04154*
X01303Y04154*
X01303Y04154*
X01303Y04154*
X01302Y04154*
X01302Y04154*
X01302Y04154*
X01301Y04154*
X01301Y04154*
X01301Y04154*
X01301Y04154*
X01301Y04154*
X013Y04154*
X013Y04155*
X013Y04155*
X01299Y04155*
X01299Y04155*
X01299Y04155*
X01298Y04155*
X01298Y04155*
X01298Y04155*
X01297Y04155*
G37*
G36*
X01292Y04124D02*
X01292D01*
X01292*
X01292*
X01292Y04124*
X01292Y04124*
X01292Y04124*
X01292Y04124*
X01292Y04124*
X01291Y04124*
X01291Y04124*
X01291Y04124*
X01291Y04124*
X01291Y04124*
X0129Y04124*
X0129Y04123*
X0129Y04123*
X0129Y04123*
X0129Y04123*
X0129Y04123*
X0129Y04123*
X0129Y04123*
X0129Y04123*
X0129Y04123*
X0129Y04122*
X0129Y04122*
X01289Y04122*
X01289Y04122*
X01289Y04122*
X01289Y04121*
X01289Y04121*
X01289Y04121*
X01289Y0412*
Y04114*
X01295*
Y0412*
X01295Y0412*
Y0412*
X01295Y0412*
X01295Y04121*
X01295Y04121*
X01295Y04121*
X01295Y04122*
X01295Y04122*
X01295Y04122*
Y04122*
X01295Y04122*
X01295Y04122*
X01295Y04122*
X01295Y04122*
X01295Y04123*
X01295Y04123*
X01295Y04123*
X01295Y04123*
X01294Y04124*
X01294Y04124*
X01294*
X01294Y04124*
X01294Y04124*
X01294Y04124*
X01294Y04124*
X01294Y04124*
X01293Y04124*
X01293Y04124*
X01293Y04124*
X01293Y04124*
X01292Y04124*
G37*
%LNgrandmaster-3*%
%LPD*%
G54D10*
X02761Y0332D02*
D01*
X02761Y03321*
X02761Y03321*
X02761Y03321*
X02761Y03322*
X02761Y03322*
X02761Y03322*
X02761Y03322*
X02761Y03323*
X0276Y03323*
X0276Y03323*
X0276Y03324*
X0276Y03324*
X02759Y03324*
X02759Y03324*
X02759Y03324*
X02759Y03325*
X02758Y03325*
X02758Y03325*
X02758Y03325*
X02757Y03325*
X02757Y03325*
X02757Y03325*
X02756*
X02756Y03325*
X02756Y03325*
X02755Y03325*
X02755Y03325*
X02755Y03325*
X02754Y03325*
X02754Y03324*
X02754Y03324*
X02753Y03324*
X02753Y03324*
X02753Y03324*
X02753Y03323*
X02752Y03323*
X02752Y03323*
X02752Y03322*
X02752Y03322*
X02752Y03322*
X02752Y03322*
X02752Y03321*
X02752Y03321*
X02751Y03321*
X02751Y0332*
X02751Y0332*
X02752Y03319*
X02752Y03319*
X02752Y03319*
X02752Y03318*
X02752Y03318*
X02752Y03318*
X02752Y03318*
X02752Y03317*
X02753Y03317*
X02753Y03317*
X02753Y03317*
X02753Y03316*
X02754Y03316*
X02754Y03316*
X02754Y03316*
X02755Y03316*
X02755Y03315*
X02755Y03315*
X02756Y03315*
X02756Y03315*
X02756Y03315*
X02757*
X02757Y03315*
X02757Y03315*
X02758Y03315*
X02758Y03315*
X02758Y03316*
X02759Y03316*
X02759Y03316*
X02759Y03316*
X02759Y03316*
X0276Y03317*
X0276Y03317*
X0276Y03317*
X0276Y03317*
X02761Y03318*
X02761Y03318*
X02761Y03318*
X02761Y03318*
X02761Y03319*
X02761Y03319*
X02761Y03319*
X02761Y0332*
X02761Y0332*
X03531Y0375D02*
D01*
X03531Y0375*
X03531Y03751*
X03531Y03751*
X03531Y03751*
X03531Y03752*
X03531Y03752*
X03531Y03752*
X03531Y03752*
X0353Y03753*
X0353Y03753*
X0353Y03753*
X0353Y03754*
X03529Y03754*
X03529Y03754*
X03529Y03754*
X03529Y03754*
X03528Y03754*
X03528Y03755*
X03528Y03755*
X03527Y03755*
X03527Y03755*
X03527Y03755*
X03526*
X03526Y03755*
X03526Y03755*
X03525Y03755*
X03525Y03755*
X03525Y03754*
X03524Y03754*
X03524Y03754*
X03524Y03754*
X03523Y03754*
X03523Y03754*
X03523Y03753*
X03523Y03753*
X03522Y03753*
X03522Y03752*
X03522Y03752*
X03522Y03752*
X03522Y03752*
X03522Y03751*
X03522Y03751*
X03522Y03751*
X03522Y0375*
X03522Y0375*
X03522Y0375*
X03522Y03749*
X03522Y03749*
X03522Y03748*
X03522Y03748*
X03522Y03748*
X03522Y03748*
X03522Y03747*
X03522Y03747*
X03523Y03747*
X03523Y03746*
X03523Y03746*
X03523Y03746*
X03524Y03746*
X03524Y03746*
X03524Y03745*
X03525Y03745*
X03525Y03745*
X03525Y03745*
X03526Y03745*
X03526Y03745*
X03526Y03745*
X03527*
X03527Y03745*
X03527Y03745*
X03528Y03745*
X03528Y03745*
X03528Y03745*
X03529Y03745*
X03529Y03746*
X03529Y03746*
X03529Y03746*
X0353Y03746*
X0353Y03746*
X0353Y03747*
X0353Y03747*
X03531Y03747*
X03531Y03748*
X03531Y03748*
X03531Y03748*
X03531Y03748*
X03531Y03749*
X03531Y03749*
X03531Y0375*
X03531Y0375*
X01636Y0423D02*
D01*
X01636Y0423*
X01636Y0423*
X01636Y04231*
X01636Y04231*
X01636Y04231*
X01636Y04232*
X01635Y04232*
X01635Y04232*
X01635Y04232*
X01635Y04233*
X01635Y04233*
X01634Y04233*
X01634Y04233*
X01634Y04234*
X01634Y04234*
X01633Y04234*
X01633Y04234*
X01633Y04234*
X01632Y04234*
X01632Y04234*
X01632Y04234*
X01631Y04234*
X01631*
X01631Y04234*
X0163Y04234*
X0163Y04234*
X0163Y04234*
X01629Y04234*
X01629Y04234*
X01629Y04234*
X01628Y04234*
X01628Y04233*
X01628Y04233*
X01628Y04233*
X01627Y04233*
X01627Y04232*
X01627Y04232*
X01627Y04232*
X01627Y04232*
X01626Y04231*
X01626Y04231*
X01626Y04231*
X01626Y0423*
X01626Y0423*
X01626Y0423*
X01626Y04229*
X01626Y04229*
X01626Y04229*
X01626Y04228*
X01626Y04228*
X01627Y04228*
X01627Y04227*
X01627Y04227*
X01627Y04227*
X01627Y04226*
X01628Y04226*
X01628Y04226*
X01628Y04226*
X01628Y04225*
X01629Y04225*
X01629Y04225*
X01629Y04225*
X0163Y04225*
X0163Y04225*
X0163Y04225*
X01631Y04225*
X01631Y04225*
X01631*
X01632Y04225*
X01632Y04225*
X01632Y04225*
X01633Y04225*
X01633Y04225*
X01633Y04225*
X01634Y04225*
X01634Y04225*
X01634Y04226*
X01634Y04226*
X01635Y04226*
X01635Y04226*
X01635Y04227*
X01635Y04227*
X01635Y04227*
X01636Y04228*
X01636Y04228*
X01636Y04228*
X01636Y04229*
X01636Y04229*
X01636Y04229*
X01636Y0423*
X04332Y00833D02*
D01*
X04332Y00834*
X04332Y00834*
X04332Y00834*
X04332Y00835*
X04332Y00835*
X04332Y00835*
X04332Y00836*
X04331Y00836*
X04331Y00836*
X04331Y00837*
X04331Y00837*
X04331Y00837*
X0433Y00837*
X0433Y00837*
X0433Y00838*
X04329Y00838*
X04329Y00838*
X04329Y00838*
X04328Y00838*
X04328Y00838*
X04328Y00838*
X04327Y00838*
X04327*
X04327Y00838*
X04326Y00838*
X04326Y00838*
X04326Y00838*
X04325Y00838*
X04325Y00838*
X04325Y00838*
X04325Y00837*
X04324Y00837*
X04324Y00837*
X04324Y00837*
X04323Y00837*
X04323Y00836*
X04323Y00836*
X04323Y00836*
X04323Y00835*
X04323Y00835*
X04323Y00835*
X04322Y00834*
X04322Y00834*
X04322Y00834*
X04322Y00833*
X04322Y00833*
X04322Y00833*
X04322Y00832*
X04323Y00832*
X04323Y00832*
X04323Y00831*
X04323Y00831*
X04323Y00831*
X04323Y0083*
X04323Y0083*
X04324Y0083*
X04324Y0083*
X04324Y00829*
X04325Y00829*
X04325Y00829*
X04325Y00829*
X04325Y00829*
X04326Y00829*
X04326Y00829*
X04326Y00829*
X04327Y00828*
X04327Y00828*
X04327*
X04328Y00828*
X04328Y00829*
X04328Y00829*
X04329Y00829*
X04329Y00829*
X04329Y00829*
X0433Y00829*
X0433Y00829*
X0433Y00829*
X04331Y0083*
X04331Y0083*
X04331Y0083*
X04331Y0083*
X04331Y00831*
X04332Y00831*
X04332Y00831*
X04332Y00832*
X04332Y00832*
X04332Y00832*
X04332Y00833*
X04332Y00833*
X04332Y00833*
X01217Y00822D02*
D01*
X01217Y00822*
X01217Y00823*
X01216Y00823*
X01216Y00823*
X01216Y00824*
X01216Y00824*
X01216Y00824*
X01216Y00825*
X01216Y00825*
X01215Y00825*
X01215Y00825*
X01215Y00826*
X01215Y00826*
X01214Y00826*
X01214Y00826*
X01214Y00826*
X01214Y00826*
X01213Y00827*
X01213Y00827*
X01213Y00827*
X01212Y00827*
X01212Y00827*
X01211*
X01211Y00827*
X01211Y00827*
X0121Y00827*
X0121Y00827*
X0121Y00826*
X0121Y00826*
X01209Y00826*
X01209Y00826*
X01209Y00826*
X01208Y00826*
X01208Y00825*
X01208Y00825*
X01208Y00825*
X01207Y00825*
X01207Y00824*
X01207Y00824*
X01207Y00824*
X01207Y00823*
X01207Y00823*
X01207Y00823*
X01207Y00822*
X01207Y00822*
X01207Y00822*
X01207Y00821*
X01207Y00821*
X01207Y00821*
X01207Y0082*
X01207Y0082*
X01207Y0082*
X01207Y00819*
X01208Y00819*
X01208Y00819*
X01208Y00818*
X01208Y00818*
X01209Y00818*
X01209Y00818*
X01209Y00818*
X0121Y00817*
X0121Y00817*
X0121Y00817*
X0121Y00817*
X01211Y00817*
X01211Y00817*
X01211Y00817*
X01212*
X01212Y00817*
X01213Y00817*
X01213Y00817*
X01213Y00817*
X01214Y00817*
X01214Y00817*
X01214Y00818*
X01214Y00818*
X01215Y00818*
X01215Y00818*
X01215Y00818*
X01215Y00819*
X01216Y00819*
X01216Y00819*
X01216Y0082*
X01216Y0082*
X01216Y0082*
X01216Y00821*
X01216Y00821*
X01217Y00821*
X01217Y00822*
X01217Y00822*
X02896Y0375D02*
D01*
X02896Y0375*
X02896Y03751*
X02896Y03751*
X02896Y03751*
X02896Y03752*
X02896Y03752*
X02896Y03752*
X02896Y03752*
X02895Y03753*
X02895Y03753*
X02895Y03753*
X02895Y03754*
X02894Y03754*
X02894Y03754*
X02894Y03754*
X02894Y03754*
X02893Y03754*
X02893Y03755*
X02893Y03755*
X02892Y03755*
X02892Y03755*
X02892Y03755*
X02891*
X02891Y03755*
X02891Y03755*
X0289Y03755*
X0289Y03755*
X0289Y03754*
X02889Y03754*
X02889Y03754*
X02889Y03754*
X02888Y03754*
X02888Y03754*
X02888Y03753*
X02888Y03753*
X02887Y03753*
X02887Y03752*
X02887Y03752*
X02887Y03752*
X02887Y03752*
X02887Y03751*
X02887Y03751*
X02887Y03751*
X02887Y0375*
X02887Y0375*
X02887Y0375*
X02887Y03749*
X02887Y03749*
X02887Y03748*
X02887Y03748*
X02887Y03748*
X02887Y03748*
X02887Y03747*
X02887Y03747*
X02888Y03747*
X02888Y03746*
X02888Y03746*
X02888Y03746*
X02889Y03746*
X02889Y03746*
X02889Y03745*
X0289Y03745*
X0289Y03745*
X0289Y03745*
X02891Y03745*
X02891Y03745*
X02891Y03745*
X02892*
X02892Y03745*
X02892Y03745*
X02893Y03745*
X02893Y03745*
X02893Y03745*
X02894Y03745*
X02894Y03746*
X02894Y03746*
X02894Y03746*
X02895Y03746*
X02895Y03746*
X02895Y03747*
X02895Y03747*
X02896Y03747*
X02896Y03748*
X02896Y03748*
X02896Y03748*
X02896Y03748*
X02896Y03749*
X02896Y03749*
X02896Y0375*
X02896Y0375*
X02781D02*
D01*
X02781Y0375*
X02781Y03751*
X02781Y03751*
X02781Y03751*
X02781Y03752*
X02781Y03752*
X02781Y03752*
X02781Y03752*
X0278Y03753*
X0278Y03753*
X0278Y03753*
X0278Y03754*
X02779Y03754*
X02779Y03754*
X02779Y03754*
X02779Y03754*
X02778Y03754*
X02778Y03755*
X02778Y03755*
X02777Y03755*
X02777Y03755*
X02777Y03755*
X02776*
X02776Y03755*
X02776Y03755*
X02775Y03755*
X02775Y03755*
X02775Y03754*
X02774Y03754*
X02774Y03754*
X02774Y03754*
X02773Y03754*
X02773Y03754*
X02773Y03753*
X02773Y03753*
X02772Y03753*
X02772Y03752*
X02772Y03752*
X02772Y03752*
X02772Y03752*
X02772Y03751*
X02772Y03751*
X02772Y03751*
X02772Y0375*
X02772Y0375*
X02772Y0375*
X02772Y03749*
X02772Y03749*
X02772Y03748*
X02772Y03748*
X02772Y03748*
X02772Y03748*
X02772Y03747*
X02772Y03747*
X02773Y03747*
X02773Y03746*
X02773Y03746*
X02773Y03746*
X02774Y03746*
X02774Y03746*
X02774Y03745*
X02775Y03745*
X02775Y03745*
X02775Y03745*
X02776Y03745*
X02776Y03745*
X02776Y03745*
X02777*
X02777Y03745*
X02777Y03745*
X02778Y03745*
X02778Y03745*
X02778Y03745*
X02779Y03745*
X02779Y03746*
X02779Y03746*
X02779Y03746*
X0278Y03746*
X0278Y03746*
X0278Y03747*
X0278Y03747*
X02781Y03747*
X02781Y03748*
X02781Y03748*
X02781Y03748*
X02781Y03748*
X02781Y03749*
X02781Y03749*
X02781Y0375*
X02781Y0375*
X03306D02*
D01*
X03306Y0375*
X03306Y03751*
X03306Y03751*
X03306Y03751*
X03306Y03752*
X03306Y03752*
X03306Y03752*
X03306Y03752*
X03305Y03753*
X03305Y03753*
X03305Y03753*
X03305Y03754*
X03304Y03754*
X03304Y03754*
X03304Y03754*
X03304Y03754*
X03303Y03754*
X03303Y03755*
X03303Y03755*
X03302Y03755*
X03302Y03755*
X03302Y03755*
X03301*
X03301Y03755*
X03301Y03755*
X033Y03755*
X033Y03755*
X033Y03754*
X03299Y03754*
X03299Y03754*
X03299Y03754*
X03298Y03754*
X03298Y03754*
X03298Y03753*
X03298Y03753*
X03297Y03753*
X03297Y03752*
X03297Y03752*
X03297Y03752*
X03297Y03752*
X03297Y03751*
X03297Y03751*
X03297Y03751*
X03297Y0375*
X03297Y0375*
X03297Y0375*
X03297Y03749*
X03297Y03749*
X03297Y03748*
X03297Y03748*
X03297Y03748*
X03297Y03748*
X03297Y03747*
X03297Y03747*
X03298Y03747*
X03298Y03746*
X03298Y03746*
X03298Y03746*
X03299Y03746*
X03299Y03746*
X03299Y03745*
X033Y03745*
X033Y03745*
X033Y03745*
X03301Y03745*
X03301Y03745*
X03301Y03745*
X03302*
X03302Y03745*
X03302Y03745*
X03303Y03745*
X03303Y03745*
X03303Y03745*
X03304Y03745*
X03304Y03746*
X03304Y03746*
X03304Y03746*
X03305Y03746*
X03305Y03746*
X03305Y03747*
X03305Y03747*
X03306Y03747*
X03306Y03748*
X03306Y03748*
X03306Y03748*
X03306Y03748*
X03306Y03749*
X03306Y03749*
X03306Y0375*
X03306Y0375*
X01217Y01872D02*
D01*
X01217Y01872*
X01217Y01873*
X01216Y01873*
X01216Y01873*
X01216Y01874*
X01216Y01874*
X01216Y01874*
X01216Y01875*
X01216Y01875*
X01215Y01875*
X01215Y01875*
X01215Y01876*
X01215Y01876*
X01214Y01876*
X01214Y01876*
X01214Y01876*
X01214Y01876*
X01213Y01877*
X01213Y01877*
X01213Y01877*
X01212Y01877*
X01212Y01877*
X01211*
X01211Y01877*
X01211Y01877*
X0121Y01877*
X0121Y01877*
X0121Y01876*
X0121Y01876*
X01209Y01876*
X01209Y01876*
X01209Y01876*
X01208Y01876*
X01208Y01875*
X01208Y01875*
X01208Y01875*
X01207Y01875*
X01207Y01874*
X01207Y01874*
X01207Y01874*
X01207Y01873*
X01207Y01873*
X01207Y01873*
X01207Y01872*
X01207Y01872*
X01207Y01872*
X01207Y01871*
X01207Y01871*
X01207Y01871*
X01207Y0187*
X01207Y0187*
X01207Y0187*
X01207Y01869*
X01208Y01869*
X01208Y01869*
X01208Y01868*
X01208Y01868*
X01209Y01868*
X01209Y01868*
X01209Y01868*
X0121Y01867*
X0121Y01867*
X0121Y01867*
X0121Y01867*
X01211Y01867*
X01211Y01867*
X01211Y01867*
X01212*
X01212Y01867*
X01213Y01867*
X01213Y01867*
X01213Y01867*
X01214Y01867*
X01214Y01867*
X01214Y01868*
X01214Y01868*
X01215Y01868*
X01215Y01868*
X01215Y01868*
X01215Y01869*
X01216Y01869*
X01216Y01869*
X01216Y0187*
X01216Y0187*
X01216Y0187*
X01216Y01871*
X01216Y01871*
X01217Y01871*
X01217Y01872*
X01217Y01872*
Y02397D02*
D01*
X01217Y02397*
X01217Y02398*
X01216Y02398*
X01216Y02398*
X01216Y02399*
X01216Y02399*
X01216Y02399*
X01216Y024*
X01216Y024*
X01215Y024*
X01215Y024*
X01215Y02401*
X01215Y02401*
X01214Y02401*
X01214Y02401*
X01214Y02401*
X01214Y02401*
X01213Y02402*
X01213Y02402*
X01213Y02402*
X01212Y02402*
X01212Y02402*
X01211*
X01211Y02402*
X01211Y02402*
X0121Y02402*
X0121Y02402*
X0121Y02401*
X0121Y02401*
X01209Y02401*
X01209Y02401*
X01209Y02401*
X01208Y02401*
X01208Y024*
X01208Y024*
X01208Y024*
X01207Y024*
X01207Y02399*
X01207Y02399*
X01207Y02399*
X01207Y02398*
X01207Y02398*
X01207Y02398*
X01207Y02397*
X01207Y02397*
X01207Y02397*
X01207Y02396*
X01207Y02396*
X01207Y02396*
X01207Y02395*
X01207Y02395*
X01207Y02395*
X01207Y02394*
X01208Y02394*
X01208Y02394*
X01208Y02393*
X01208Y02393*
X01209Y02393*
X01209Y02393*
X01209Y02393*
X0121Y02392*
X0121Y02392*
X0121Y02392*
X0121Y02392*
X01211Y02392*
X01211Y02392*
X01211Y02392*
X01212*
X01212Y02392*
X01213Y02392*
X01213Y02392*
X01213Y02392*
X01214Y02392*
X01214Y02392*
X01214Y02393*
X01214Y02393*
X01215Y02393*
X01215Y02393*
X01215Y02393*
X01215Y02394*
X01216Y02394*
X01216Y02394*
X01216Y02395*
X01216Y02395*
X01216Y02395*
X01216Y02396*
X01216Y02396*
X01217Y02396*
X01217Y02397*
X01217Y02397*
Y01347D02*
D01*
X01217Y01347*
X01217Y01348*
X01216Y01348*
X01216Y01348*
X01216Y01349*
X01216Y01349*
X01216Y01349*
X01216Y0135*
X01216Y0135*
X01215Y0135*
X01215Y0135*
X01215Y01351*
X01215Y01351*
X01214Y01351*
X01214Y01351*
X01214Y01351*
X01214Y01351*
X01213Y01352*
X01213Y01352*
X01213Y01352*
X01212Y01352*
X01212Y01352*
X01211*
X01211Y01352*
X01211Y01352*
X0121Y01352*
X0121Y01352*
X0121Y01351*
X0121Y01351*
X01209Y01351*
X01209Y01351*
X01209Y01351*
X01208Y01351*
X01208Y0135*
X01208Y0135*
X01208Y0135*
X01207Y0135*
X01207Y01349*
X01207Y01349*
X01207Y01349*
X01207Y01348*
X01207Y01348*
X01207Y01348*
X01207Y01347*
X01207Y01347*
X01207Y01347*
X01207Y01346*
X01207Y01346*
X01207Y01346*
X01207Y01345*
X01207Y01345*
X01207Y01345*
X01207Y01344*
X01208Y01344*
X01208Y01344*
X01208Y01343*
X01208Y01343*
X01209Y01343*
X01209Y01343*
X01209Y01343*
X0121Y01342*
X0121Y01342*
X0121Y01342*
X0121Y01342*
X01211Y01342*
X01211Y01342*
X01211Y01342*
X01212*
X01212Y01342*
X01213Y01342*
X01213Y01342*
X01213Y01342*
X01214Y01342*
X01214Y01342*
X01214Y01343*
X01214Y01343*
X01215Y01343*
X01215Y01343*
X01215Y01343*
X01215Y01344*
X01216Y01344*
X01216Y01344*
X01216Y01345*
X01216Y01345*
X01216Y01345*
X01216Y01346*
X01216Y01346*
X01217Y01346*
X01217Y01347*
X01217Y01347*
X03777Y03889D02*
D01*
X03777Y03889*
X03777Y03889*
X03777Y0389*
X03777Y0389*
X03777Y0389*
X03777Y03891*
X03776Y03891*
X03776Y03891*
X03776Y03891*
X03776Y03892*
X03776Y03892*
X03775Y03892*
X03775Y03892*
X03775Y03893*
X03775Y03893*
X03774Y03893*
X03774Y03893*
X03774Y03893*
X03773Y03893*
X03773Y03893*
X03773Y03893*
X03772Y03893*
X03772*
X03772Y03893*
X03771Y03893*
X03771Y03893*
X03771Y03893*
X0377Y03893*
X0377Y03893*
X0377Y03893*
X03769Y03893*
X03769Y03892*
X03769Y03892*
X03769Y03892*
X03768Y03892*
X03768Y03891*
X03768Y03891*
X03768Y03891*
X03768Y03891*
X03767Y0389*
X03767Y0389*
X03767Y0389*
X03767Y03889*
X03767Y03889*
X03767Y03889*
X03767Y03888*
X03767Y03888*
X03767Y03888*
X03767Y03887*
X03767Y03887*
X03768Y03887*
X03768Y03886*
X03768Y03886*
X03768Y03886*
X03768Y03885*
X03769Y03885*
X03769Y03885*
X03769Y03885*
X03769Y03885*
X0377Y03884*
X0377Y03884*
X0377Y03884*
X03771Y03884*
X03771Y03884*
X03771Y03884*
X03772Y03884*
X03772Y03884*
X03772*
X03773Y03884*
X03773Y03884*
X03773Y03884*
X03774Y03884*
X03774Y03884*
X03774Y03884*
X03775Y03884*
X03775Y03885*
X03775Y03885*
X03775Y03885*
X03776Y03885*
X03776Y03885*
X03776Y03886*
X03776Y03886*
X03776Y03886*
X03777Y03887*
X03777Y03887*
X03777Y03887*
X03777Y03888*
X03777Y03888*
X03777Y03888*
X03777Y03889*
G54D11*
X02863Y03279D02*
D01*
X02863Y0328*
X02863Y03281*
X02862Y03281*
X02862Y03282*
X02862Y03283*
X02862Y03284*
X02861Y03285*
X02861Y03285*
X0286Y03286*
X0286Y03287*
X02859Y03287*
X02859Y03288*
X02858Y03288*
X02857Y03289*
X02857Y03289*
X02856Y0329*
X02855Y0329*
X02855Y0329*
X02854Y0329*
X02853Y03291*
X02852Y03291*
X02851Y03291*
X0285*
X0285Y03291*
X02849Y03291*
X02848Y0329*
X02847Y0329*
X02846Y0329*
X02846Y0329*
X02845Y03289*
X02844Y03289*
X02844Y03288*
X02843Y03288*
X02842Y03287*
X02842Y03287*
X02841Y03286*
X02841Y03285*
X0284Y03285*
X0284Y03284*
X0284Y03283*
X0284Y03282*
X02839Y03281*
X02839Y03281*
X02839Y0328*
X02839Y03279*
X02839Y03278*
X02839Y03277*
X02839Y03277*
X0284Y03276*
X0284Y03275*
X0284Y03274*
X0284Y03273*
X02841Y03273*
X02841Y03272*
X02842Y03271*
X02842Y03271*
X02843Y0327*
X02844Y0327*
X02844Y03269*
X02845Y03269*
X02846Y03268*
X02846Y03268*
X02847Y03268*
X02848Y03268*
X02849Y03267*
X0285Y03267*
X0285Y03267*
X02851*
X02852Y03267*
X02853Y03267*
X02854Y03268*
X02855Y03268*
X02855Y03268*
X02856Y03268*
X02857Y03269*
X02857Y03269*
X02858Y0327*
X02859Y0327*
X02859Y03271*
X0286Y03271*
X0286Y03272*
X02861Y03273*
X02861Y03273*
X02862Y03274*
X02862Y03275*
X02862Y03276*
X02862Y03277*
X02863Y03277*
X02863Y03278*
X02863Y03279*
X01727Y04171D02*
D01*
X01727Y04171*
X01726Y04172*
X01726Y04173*
X01726Y04174*
X01726Y04175*
X01726Y04175*
X01725Y04176*
X01725Y04177*
X01724Y04178*
X01724Y04178*
X01723Y04179*
X01723Y04179*
X01722Y0418*
X01721Y0418*
X01721Y04181*
X0172Y04181*
X01719Y04182*
X01718Y04182*
X01718Y04182*
X01717Y04182*
X01716Y04182*
X01715Y04182*
X01714*
X01713Y04182*
X01713Y04182*
X01712Y04182*
X01711Y04182*
X0171Y04182*
X0171Y04181*
X01709Y04181*
X01708Y0418*
X01707Y0418*
X01707Y04179*
X01706Y04179*
X01706Y04178*
X01705Y04178*
X01705Y04177*
X01704Y04176*
X01704Y04175*
X01704Y04175*
X01703Y04174*
X01703Y04173*
X01703Y04172*
X01703Y04171*
X01703Y04171*
X01703Y0417*
X01703Y04169*
X01703Y04168*
X01703Y04167*
X01704Y04167*
X01704Y04166*
X01704Y04165*
X01705Y04164*
X01705Y04164*
X01706Y04163*
X01706Y04162*
X01707Y04162*
X01707Y04161*
X01708Y04161*
X01709Y0416*
X0171Y0416*
X0171Y0416*
X01711Y04159*
X01712Y04159*
X01713Y04159*
X01713Y04159*
X01714Y04159*
X01715*
X01716Y04159*
X01717Y04159*
X01718Y04159*
X01718Y04159*
X01719Y0416*
X0172Y0416*
X01721Y0416*
X01721Y04161*
X01722Y04161*
X01723Y04162*
X01723Y04162*
X01724Y04163*
X01724Y04164*
X01725Y04164*
X01725Y04165*
X01726Y04166*
X01726Y04167*
X01726Y04167*
X01726Y04168*
X01726Y04169*
X01727Y0417*
X01727Y04171*
X03868Y0383D02*
D01*
X03868Y0383*
X03867Y03831*
X03867Y03832*
X03867Y03833*
X03867Y03834*
X03867Y03834*
X03866Y03835*
X03866Y03836*
X03865Y03837*
X03865Y03837*
X03864Y03838*
X03864Y03838*
X03863Y03839*
X03862Y03839*
X03862Y0384*
X03861Y0384*
X0386Y03841*
X03859Y03841*
X03859Y03841*
X03858Y03841*
X03857Y03841*
X03856Y03841*
X03855*
X03854Y03841*
X03854Y03841*
X03853Y03841*
X03852Y03841*
X03851Y03841*
X03851Y0384*
X0385Y0384*
X03849Y03839*
X03848Y03839*
X03848Y03838*
X03847Y03838*
X03847Y03837*
X03846Y03837*
X03846Y03836*
X03845Y03835*
X03845Y03834*
X03845Y03834*
X03844Y03833*
X03844Y03832*
X03844Y03831*
X03844Y0383*
X03844Y0383*
X03844Y03829*
X03844Y03828*
X03844Y03827*
X03844Y03826*
X03845Y03826*
X03845Y03825*
X03845Y03824*
X03846Y03823*
X03846Y03823*
X03847Y03822*
X03847Y03821*
X03848Y03821*
X03848Y0382*
X03849Y0382*
X0385Y03819*
X03851Y03819*
X03851Y03819*
X03852Y03818*
X03853Y03818*
X03854Y03818*
X03854Y03818*
X03855Y03818*
X03856*
X03857Y03818*
X03858Y03818*
X03859Y03818*
X03859Y03818*
X0386Y03819*
X03861Y03819*
X03862Y03819*
X03862Y0382*
X03863Y0382*
X03864Y03821*
X03864Y03821*
X03865Y03822*
X03865Y03823*
X03866Y03823*
X03866Y03824*
X03867Y03825*
X03867Y03826*
X03867Y03826*
X03867Y03827*
X03867Y03828*
X03868Y03829*
X03868Y0383*
G54D12*
X06191Y03733D02*
D01*
X06191Y03733*
X06191Y03733*
X06191Y03733*
X06191Y03734*
X0619Y03734*
X0619Y03734*
X0619Y03734*
X0619Y03734*
X0619Y03734*
X0619Y03734*
X0619Y03734*
X0619Y03735*
X0619Y03735*
X0619Y03735*
X0619Y03735*
X06189Y03735*
X06189Y03735*
X06189Y03735*
X06189Y03735*
X06189Y03735*
X06189Y03735*
X06189Y03735*
X06189*
X06188Y03735*
X06188Y03735*
X06188Y03735*
X06188Y03735*
X06188Y03735*
X06188Y03735*
X06188Y03735*
X06188Y03735*
X06187Y03735*
X06187Y03735*
X06187Y03734*
X06187Y03734*
X06187Y03734*
X06187Y03734*
X06187Y03734*
X06187Y03734*
X06187Y03734*
X06187Y03734*
X06187Y03733*
X06187Y03733*
X06187Y03733*
X06187Y03733*
X06187Y03733*
X06187Y03733*
X06187Y03733*
X06187Y03732*
X06187Y03732*
X06187Y03732*
X06187Y03732*
X06187Y03732*
X06187Y03732*
X06187Y03732*
X06187Y03732*
X06187Y03732*
X06187Y03731*
X06188Y03731*
X06188Y03731*
X06188Y03731*
X06188Y03731*
X06188Y03731*
X06188Y03731*
X06188Y03731*
X06188Y03731*
X06189Y03731*
X06189*
X06189Y03731*
X06189Y03731*
X06189Y03731*
X06189Y03731*
X06189Y03731*
X06189Y03731*
X0619Y03731*
X0619Y03731*
X0619Y03731*
X0619Y03732*
X0619Y03732*
X0619Y03732*
X0619Y03732*
X0619Y03732*
X0619Y03732*
X0619Y03732*
X0619Y03732*
X06191Y03732*
X06191Y03733*
X06191Y03733*
X06191Y03733*
X06191Y03733*
X01223Y04175D02*
D01*
X01223Y04176*
X01223Y04176*
X01223Y04176*
X01223Y04176*
X01223Y04176*
X01223Y04176*
X01223Y04176*
X01222Y04176*
X01222Y04177*
X01222Y04177*
X01222Y04177*
X01222Y04177*
X01222Y04177*
X01222Y04177*
X01222Y04177*
X01222Y04177*
X01222Y04177*
X01221Y04177*
X01221Y04177*
X01221Y04177*
X01221Y04177*
X01221Y04177*
X01221*
X01221Y04177*
X0122Y04177*
X0122Y04177*
X0122Y04177*
X0122Y04177*
X0122Y04177*
X0122Y04177*
X0122Y04177*
X0122Y04177*
X01219Y04177*
X01219Y04177*
X01219Y04177*
X01219Y04177*
X01219Y04176*
X01219Y04176*
X01219Y04176*
X01219Y04176*
X01219Y04176*
X01219Y04176*
X01219Y04176*
X01219Y04176*
X01219Y04175*
X01219Y04175*
X01219Y04175*
X01219Y04175*
X01219Y04175*
X01219Y04175*
X01219Y04175*
X01219Y04174*
X01219Y04174*
X01219Y04174*
X01219Y04174*
X01219Y04174*
X01219Y04174*
X0122Y04174*
X0122Y04174*
X0122Y04174*
X0122Y04174*
X0122Y04174*
X0122Y04173*
X0122Y04173*
X0122Y04173*
X01221Y04173*
X01221Y04173*
X01221*
X01221Y04173*
X01221Y04173*
X01221Y04173*
X01221Y04173*
X01222Y04174*
X01222Y04174*
X01222Y04174*
X01222Y04174*
X01222Y04174*
X01222Y04174*
X01222Y04174*
X01222Y04174*
X01222Y04174*
X01222Y04174*
X01223Y04174*
X01223Y04175*
X01223Y04175*
X01223Y04175*
X01223Y04175*
X01223Y04175*
X01223Y04175*
X01223Y04175*
X03247Y02866D02*
D01*
X03247Y02866*
X03247Y02865*
X03247Y02865*
X03247Y02865*
X03247Y02865*
X03247Y02865*
X03247Y02865*
X03247Y02865*
X03247Y02864*
X03247Y02864*
X03247Y02864*
X03247Y02864*
X03247Y02864*
X03247Y02864*
X03248Y02864*
X03248Y02864*
X03248Y02864*
X03248Y02864*
X03248Y02864*
X03248Y02864*
X03248Y02864*
X03248Y02864*
X03249*
X03249Y02864*
X03249Y02864*
X03249Y02864*
X03249Y02864*
X03249Y02864*
X03249Y02864*
X0325Y02864*
X0325Y02864*
X0325Y02864*
X0325Y02864*
X0325Y02864*
X0325Y02864*
X0325Y02864*
X0325Y02865*
X0325Y02865*
X0325Y02865*
X0325Y02865*
X0325Y02865*
X0325Y02865*
X0325Y02865*
X0325Y02866*
X0325Y02866*
D01*
X0325Y02866*
X0325Y02866*
X0325Y02866*
X0325Y02866*
X0325Y02866*
X0325Y02866*
X0325Y02867*
X0325Y02867*
X0325Y02867*
X0325Y02867*
X0325Y02867*
X0325Y02867*
X0325Y02867*
X0325Y02867*
X03249Y02867*
X03249Y02867*
X03249Y02867*
X03249Y02868*
X03249Y02868*
X03249Y02868*
X03249Y02868*
X03249Y02868*
X03248*
X03248Y02868*
X03248Y02868*
X03248Y02868*
X03248Y02868*
X03248Y02867*
X03248Y02867*
X03248Y02867*
X03247Y02867*
X03247Y02867*
X03247Y02867*
X03247Y02867*
X03247Y02867*
X03247Y02867*
X03247Y02867*
X03247Y02867*
X03247Y02866*
X03247Y02866*
X03247Y02866*
X03247Y02866*
X03247Y02866*
X03247Y02866*
X03247Y02866*
X05881Y03733D02*
D01*
X05881Y03733*
X05881Y03733*
X05881Y03733*
X05881Y03734*
X0588Y03734*
X0588Y03734*
X0588Y03734*
X0588Y03734*
X0588Y03734*
X0588Y03734*
X0588Y03734*
X0588Y03735*
X0588Y03735*
X0588Y03735*
X0588Y03735*
X05879Y03735*
X05879Y03735*
X05879Y03735*
X05879Y03735*
X05879Y03735*
X05879Y03735*
X05879Y03735*
X05879*
X05878Y03735*
X05878Y03735*
X05878Y03735*
X05878Y03735*
X05878Y03735*
X05878Y03735*
X05878Y03735*
X05878Y03735*
X05877Y03735*
X05877Y03735*
X05877Y03734*
X05877Y03734*
X05877Y03734*
X05877Y03734*
X05877Y03734*
X05877Y03734*
X05877Y03734*
X05877Y03734*
X05877Y03733*
X05877Y03733*
X05877Y03733*
X05877Y03733*
X05877Y03733*
X05877Y03733*
X05877Y03733*
X05877Y03732*
X05877Y03732*
X05877Y03732*
X05877Y03732*
X05877Y03732*
X05877Y03732*
X05877Y03732*
X05877Y03732*
X05877Y03732*
X05877Y03731*
X05878Y03731*
X05878Y03731*
X05878Y03731*
X05878Y03731*
X05878Y03731*
X05878Y03731*
X05878Y03731*
X05878Y03731*
X05879Y03731*
X05879*
X05879Y03731*
X05879Y03731*
X05879Y03731*
X05879Y03731*
X05879Y03731*
X05879Y03731*
X0588Y03731*
X0588Y03731*
X0588Y03731*
X0588Y03732*
X0588Y03732*
X0588Y03732*
X0588Y03732*
X0588Y03732*
X0588Y03732*
X0588Y03732*
X0588Y03732*
X05881Y03732*
X05881Y03733*
X05881Y03733*
X05881Y03733*
X05881Y03733*
X06196Y03598D02*
D01*
X06196Y03598*
X06196Y03598*
X06196Y03598*
X06196Y03599*
X06195Y03599*
X06195Y03599*
X06195Y03599*
X06195Y03599*
X06195Y03599*
X06195Y03599*
X06195Y03599*
X06195Y036*
X06195Y036*
X06195Y036*
X06195Y036*
X06194Y036*
X06194Y036*
X06194Y036*
X06194Y036*
X06194Y036*
X06194Y036*
X06194Y036*
X06194*
X06193Y036*
X06193Y036*
X06193Y036*
X06193Y036*
X06193Y036*
X06193Y036*
X06193Y036*
X06193Y036*
X06192Y036*
X06192Y036*
X06192Y03599*
X06192Y03599*
X06192Y03599*
X06192Y03599*
X06192Y03599*
X06192Y03599*
X06192Y03599*
X06192Y03599*
X06192Y03598*
X06192Y03598*
X06192Y03598*
X06192Y03598*
X06192Y03598*
X06192Y03598*
X06192Y03598*
X06192Y03597*
X06192Y03597*
X06192Y03597*
X06192Y03597*
X06192Y03597*
X06192Y03597*
X06192Y03597*
X06192Y03597*
X06192Y03597*
X06192Y03596*
X06193Y03596*
X06193Y03596*
X06193Y03596*
X06193Y03596*
X06193Y03596*
X06193Y03596*
X06193Y03596*
X06193Y03596*
X06194Y03596*
X06194*
X06194Y03596*
X06194Y03596*
X06194Y03596*
X06194Y03596*
X06194Y03596*
X06194Y03596*
X06195Y03596*
X06195Y03596*
X06195Y03596*
X06195Y03597*
X06195Y03597*
X06195Y03597*
X06195Y03597*
X06195Y03597*
X06195Y03597*
X06195Y03597*
X06195Y03597*
X06196Y03597*
X06196Y03598*
X06196Y03598*
X06196Y03598*
X06196Y03598*
X04255Y03631D02*
D01*
X04255Y03632*
X04255Y03632*
X04255Y03632*
X04255Y03632*
X04255Y03632*
X04255Y03632*
X04255Y03632*
X04255Y03632*
X04255Y03633*
X04255Y03633*
X04255Y03633*
X04255Y03633*
X04255Y03633*
X04255Y03633*
X04254Y03633*
X04254Y03633*
X04254Y03633*
X04254Y03633*
X04254Y03633*
X04254Y03633*
X04254Y03633*
X04254Y03633*
X04253*
X04253Y03633*
X04253Y03633*
X04253Y03633*
X04253Y03633*
X04253Y03633*
X04253Y03633*
X04252Y03633*
X04252Y03633*
X04252Y03633*
X04252Y03633*
X04252Y03633*
X04252Y03633*
X04252Y03633*
X04252Y03632*
X04252Y03632*
X04252Y03632*
X04252Y03632*
X04252Y03632*
X04252Y03632*
X04251Y03632*
X04251Y03632*
X04251Y03631*
X04251Y03631*
X04251Y03631*
X04252Y03631*
X04252Y03631*
X04252Y03631*
X04252Y03631*
X04252Y0363*
X04252Y0363*
X04252Y0363*
X04252Y0363*
X04252Y0363*
X04252Y0363*
X04252Y0363*
X04252Y0363*
X04252Y0363*
X04253Y0363*
X04253Y0363*
X04253Y0363*
X04253Y03629*
X04253Y03629*
X04253Y03629*
X04253Y03629*
X04254*
X04254Y03629*
X04254Y03629*
X04254Y03629*
X04254Y0363*
X04254Y0363*
X04254Y0363*
X04254Y0363*
X04255Y0363*
X04255Y0363*
X04255Y0363*
X04255Y0363*
X04255Y0363*
X04255Y0363*
X04255Y0363*
X04255Y0363*
X04255Y03631*
X04255Y03631*
X04255Y03631*
X04255Y03631*
X04255Y03631*
X04255Y03631*
X04255Y03631*
X0362Y03931D02*
D01*
X0362Y03931*
X0362Y03931*
X0362Y03931*
X0362Y03931*
X0362Y03931*
X0362Y03932*
X0362Y03932*
X0362Y03932*
X03619Y03932*
X03619Y03932*
X03619Y03932*
X03619Y03932*
X03619Y03932*
X03619Y03932*
X03619Y03932*
X03619Y03933*
X03619Y03933*
X03618Y03933*
X03618Y03933*
X03618Y03933*
X03618Y03933*
X03618Y03933*
X03618*
X03618Y03933*
X03618Y03933*
X03617Y03933*
X03617Y03933*
X03617Y03933*
X03617Y03933*
X03617Y03932*
X03617Y03932*
X03617Y03932*
X03617Y03932*
X03616Y03932*
X03616Y03932*
X03616Y03932*
X03616Y03932*
X03616Y03932*
X03616Y03932*
X03616Y03931*
X03616Y03931*
X03616Y03931*
X03616Y03931*
X03616Y03931*
X03616Y03931*
X03616Y03931*
X03616Y0393*
X03616Y0393*
X03616Y0393*
X03616Y0393*
X03616Y0393*
X03616Y0393*
X03616Y0393*
X03616Y0393*
X03616Y03929*
X03616Y03929*
X03617Y03929*
X03617Y03929*
X03617Y03929*
X03617Y03929*
X03617Y03929*
X03617Y03929*
X03617Y03929*
X03617Y03929*
X03618Y03929*
X03618Y03929*
X03618Y03929*
X03618*
X03618Y03929*
X03618Y03929*
X03618Y03929*
X03618Y03929*
X03619Y03929*
X03619Y03929*
X03619Y03929*
X03619Y03929*
X03619Y03929*
X03619Y03929*
X03619Y03929*
X03619Y03929*
X03619Y0393*
X0362Y0393*
X0362Y0393*
X0362Y0393*
X0362Y0393*
X0362Y0393*
X0362Y0393*
X0362Y0393*
X0362Y03931*
X0362Y03931*
X03563Y03705D02*
D01*
X03563Y03706*
X03563Y03706*
X03563Y03706*
X03563Y03706*
X03563Y03706*
X03563Y03706*
X03563Y03706*
X03562Y03706*
X03562Y03707*
X03562Y03707*
X03562Y03707*
X03562Y03707*
X03562Y03707*
X03562Y03707*
X03562Y03707*
X03562Y03707*
X03562Y03707*
X03561Y03707*
X03561Y03707*
X03561Y03707*
X03561Y03707*
X03561Y03707*
X03561*
X03561Y03707*
X0356Y03707*
X0356Y03707*
X0356Y03707*
X0356Y03707*
X0356Y03707*
X0356Y03707*
X0356Y03707*
X0356Y03707*
X03559Y03707*
X03559Y03707*
X03559Y03707*
X03559Y03707*
X03559Y03706*
X03559Y03706*
X03559Y03706*
X03559Y03706*
X03559Y03706*
X03559Y03706*
X03559Y03706*
X03559Y03706*
X03559Y03705*
X03559Y03705*
X03559Y03705*
X03559Y03705*
X03559Y03705*
X03559Y03705*
X03559Y03705*
X03559Y03704*
X03559Y03704*
X03559Y03704*
X03559Y03704*
X03559Y03704*
X03559Y03704*
X0356Y03704*
X0356Y03704*
X0356Y03704*
X0356Y03704*
X0356Y03704*
X0356Y03703*
X0356Y03703*
X0356Y03703*
X03561Y03703*
X03561Y03703*
X03561*
X03561Y03703*
X03561Y03703*
X03561Y03703*
X03561Y03703*
X03562Y03704*
X03562Y03704*
X03562Y03704*
X03562Y03704*
X03562Y03704*
X03562Y03704*
X03562Y03704*
X03562Y03704*
X03562Y03704*
X03562Y03704*
X03563Y03704*
X03563Y03705*
X03563Y03705*
X03563Y03705*
X03563Y03705*
X03563Y03705*
X03563Y03705*
X03563Y03705*
X00618Y04175D02*
D01*
X00618Y04176*
X00618Y04176*
X00618Y04176*
X00618Y04176*
X00618Y04176*
X00618Y04176*
X00618Y04176*
X00617Y04176*
X00617Y04177*
X00617Y04177*
X00617Y04177*
X00617Y04177*
X00617Y04177*
X00617Y04177*
X00617Y04177*
X00617Y04177*
X00617Y04177*
X00616Y04177*
X00616Y04177*
X00616Y04177*
X00616Y04177*
X00616Y04177*
X00616*
X00616Y04177*
X00615Y04177*
X00615Y04177*
X00615Y04177*
X00615Y04177*
X00615Y04177*
X00615Y04177*
X00615Y04177*
X00615Y04177*
X00614Y04177*
X00614Y04177*
X00614Y04177*
X00614Y04177*
X00614Y04176*
X00614Y04176*
X00614Y04176*
X00614Y04176*
X00614Y04176*
X00614Y04176*
X00614Y04176*
X00614Y04176*
X00614Y04175*
X00614Y04175*
X00614Y04175*
X00614Y04175*
X00614Y04175*
X00614Y04175*
X00614Y04175*
X00614Y04174*
X00614Y04174*
X00614Y04174*
X00614Y04174*
X00614Y04174*
X00614Y04174*
X00615Y04174*
X00615Y04174*
X00615Y04174*
X00615Y04174*
X00615Y04174*
X00615Y04173*
X00615Y04173*
X00615Y04173*
X00616Y04173*
X00616Y04173*
X00616*
X00616Y04173*
X00616Y04173*
X00616Y04173*
X00616Y04173*
X00617Y04174*
X00617Y04174*
X00617Y04174*
X00617Y04174*
X00617Y04174*
X00617Y04174*
X00617Y04174*
X00617Y04174*
X00617Y04174*
X00617Y04174*
X00618Y04174*
X00618Y04175*
X00618Y04175*
X00618Y04175*
X00618Y04175*
X00618Y04175*
X00618Y04175*
X00618Y04175*
X00819D02*
D01*
X00819Y04176*
X00819Y04176*
X00819Y04176*
X00819Y04176*
X00819Y04176*
X00819Y04176*
X00819Y04176*
X00819Y04176*
X00819Y04177*
X00819Y04177*
X00819Y04177*
X00819Y04177*
X00819Y04177*
X00819Y04177*
X00818Y04177*
X00818Y04177*
X00818Y04177*
X00818Y04177*
X00818Y04177*
X00818Y04177*
X00818Y04177*
X00818Y04177*
X00817*
X00817Y04177*
X00817Y04177*
X00817Y04177*
X00817Y04177*
X00817Y04177*
X00817Y04177*
X00816Y04177*
X00816Y04177*
X00816Y04177*
X00816Y04177*
X00816Y04177*
X00816Y04177*
X00816Y04177*
X00816Y04176*
X00816Y04176*
X00816Y04176*
X00816Y04176*
X00816Y04176*
X00816Y04176*
X00816Y04176*
X00815Y04176*
X00815Y04175*
X00815Y04175*
X00816Y04175*
X00816Y04175*
X00816Y04175*
X00816Y04175*
X00816Y04175*
X00816Y04174*
X00816Y04174*
X00816Y04174*
X00816Y04174*
X00816Y04174*
X00816Y04174*
X00816Y04174*
X00816Y04174*
X00816Y04174*
X00817Y04174*
X00817Y04174*
X00817Y04173*
X00817Y04173*
X00817Y04173*
X00817Y04173*
X00817Y04173*
X00818*
X00818Y04173*
X00818Y04173*
X00818Y04173*
X00818Y04173*
X00818Y04174*
X00818Y04174*
X00818Y04174*
X00819Y04174*
X00819Y04174*
X00819Y04174*
X00819Y04174*
X00819Y04174*
X00819Y04174*
X00819Y04174*
X00819Y04174*
X00819Y04175*
X00819Y04175*
X00819Y04175*
X00819Y04175*
X00819Y04175*
X00819Y04175*
X00819Y04175*
X01021D02*
D01*
X01021Y04176*
X01021Y04176*
X01021Y04176*
X01021Y04176*
X01021Y04176*
X01021Y04176*
X01021Y04176*
X01021Y04176*
X01021Y04177*
X01021Y04177*
X01021Y04177*
X0102Y04177*
X0102Y04177*
X0102Y04177*
X0102Y04177*
X0102Y04177*
X0102Y04177*
X0102Y04177*
X0102Y04177*
X01019Y04177*
X01019Y04177*
X01019Y04177*
X01019*
X01019Y04177*
X01019Y04177*
X01019Y04177*
X01019Y04177*
X01018Y04177*
X01018Y04177*
X01018Y04177*
X01018Y04177*
X01018Y04177*
X01018Y04177*
X01018Y04177*
X01018Y04177*
X01018Y04177*
X01017Y04176*
X01017Y04176*
X01017Y04176*
X01017Y04176*
X01017Y04176*
X01017Y04176*
X01017Y04176*
X01017Y04176*
X01017Y04175*
X01017Y04175*
X01017Y04175*
X01017Y04175*
X01017Y04175*
X01017Y04175*
X01017Y04175*
X01017Y04174*
X01017Y04174*
X01018Y04174*
X01018Y04174*
X01018Y04174*
X01018Y04174*
X01018Y04174*
X01018Y04174*
X01018Y04174*
X01018Y04174*
X01018Y04174*
X01019Y04173*
X01019Y04173*
X01019Y04173*
X01019Y04173*
X01019Y04173*
X01019*
X01019Y04173*
X01019Y04173*
X0102Y04173*
X0102Y04173*
X0102Y04174*
X0102Y04174*
X0102Y04174*
X0102Y04174*
X0102Y04174*
X0102Y04174*
X01021Y04174*
X01021Y04174*
X01021Y04174*
X01021Y04174*
X01021Y04174*
X01021Y04175*
X01021Y04175*
X01021Y04175*
X01021Y04175*
X01021Y04175*
X01021Y04175*
X01021Y04175*
X03278Y02846D02*
Y02854D01*
X03258D02*
X03278D01*
Y02775D02*
Y02783D01*
X03258Y02775D02*
X03278D01*
X03199D02*
X03219D01*
X03199D02*
Y02783D01*
Y02846D02*
Y02854D01*
X03219*
G54D13*
X06679Y03131D02*
D01*
X06679Y03131*
X06679Y03131*
X06679Y03132*
X06679Y03132*
X06679Y03132*
X06679Y03133*
X06679Y03133*
X06679Y03133*
X06678Y03133*
X06678Y03134*
X06678Y03134*
X06678Y03134*
X06677Y03135*
X06677Y03135*
X06677Y03135*
X06677Y03135*
X06676Y03135*
X06676Y03135*
X06676Y03135*
X06675Y03135*
X06675Y03136*
X06675Y03136*
X06674*
X06674Y03136*
X06673Y03135*
X06673Y03135*
X06673Y03135*
X06672Y03135*
X06672Y03135*
X06672Y03135*
X06672Y03135*
X06671Y03135*
X06671Y03134*
X06671Y03134*
X06671Y03134*
X0667Y03133*
X0667Y03133*
X0667Y03133*
X0667Y03133*
X0667Y03132*
X0667Y03132*
X06669Y03132*
X06669Y03131*
X06669Y03131*
X06669Y03131*
X06669Y0313*
X06669Y0313*
X06669Y0313*
X0667Y03129*
X0667Y03129*
X0667Y03129*
X0667Y03128*
X0667Y03128*
X0667Y03128*
X06671Y03127*
X06671Y03127*
X06671Y03127*
X06671Y03127*
X06672Y03126*
X06672Y03126*
X06672Y03126*
X06672Y03126*
X06673Y03126*
X06673Y03126*
X06673Y03126*
X06674Y03126*
X06674Y03126*
X06675*
X06675Y03126*
X06675Y03126*
X06676Y03126*
X06676Y03126*
X06676Y03126*
X06677Y03126*
X06677Y03126*
X06677Y03126*
X06677Y03127*
X06678Y03127*
X06678Y03127*
X06678Y03127*
X06678Y03128*
X06679Y03128*
X06679Y03128*
X06679Y03129*
X06679Y03129*
X06679Y03129*
X06679Y0313*
X06679Y0313*
X06679Y0313*
X06679Y03131*
X04129Y01599D02*
D01*
X04129Y01599*
X04129Y016*
X04129Y016*
X04129Y016*
X04129Y01601*
X04129Y01601*
X04129Y01601*
X04129Y01602*
X04128Y01602*
X04128Y01602*
X04128Y01603*
X04128Y01603*
X04127Y01603*
X04127Y01603*
X04127Y01603*
X04127Y01604*
X04126Y01604*
X04126Y01604*
X04126Y01604*
X04125Y01604*
X04125Y01604*
X04124Y01604*
X04124*
X04124Y01604*
X04123Y01604*
X04123Y01604*
X04123Y01604*
X04122Y01604*
X04122Y01604*
X04122Y01603*
X04122Y01603*
X04121Y01603*
X04121Y01603*
X04121Y01603*
X0412Y01602*
X0412Y01602*
X0412Y01602*
X0412Y01601*
X0412Y01601*
X0412Y01601*
X0412Y016*
X04119Y016*
X04119Y016*
X04119Y01599*
X04119Y01599*
X04119Y01599*
X04119Y01598*
X04119Y01598*
X0412Y01598*
X0412Y01597*
X0412Y01597*
X0412Y01597*
X0412Y01596*
X0412Y01596*
X0412Y01596*
X04121Y01596*
X04121Y01595*
X04121Y01595*
X04122Y01595*
X04122Y01595*
X04122Y01595*
X04122Y01594*
X04123Y01594*
X04123Y01594*
X04123Y01594*
X04124Y01594*
X04124Y01594*
X04124*
X04125Y01594*
X04125Y01594*
X04126Y01594*
X04126Y01594*
X04126Y01594*
X04127Y01595*
X04127Y01595*
X04127Y01595*
X04127Y01595*
X04128Y01595*
X04128Y01596*
X04128Y01596*
X04128Y01596*
X04129Y01596*
X04129Y01597*
X04129Y01597*
X04129Y01597*
X04129Y01598*
X04129Y01598*
X04129Y01598*
X04129Y01599*
X04129Y01599*
X0021Y02829D02*
D01*
X0021Y02834*
X00209Y02838*
X00209Y02842*
X00208Y02846*
X00206Y0285*
X00205Y02854*
X00203Y02858*
X00201Y02862*
X00198Y02865*
X00196Y02869*
X00193Y02872*
X0019Y02875*
X00187Y02878*
X00183Y0288*
X0018Y02882*
X00176Y02884*
X00172Y02886*
X00168Y02887*
X00164Y02889*
X0016Y0289*
X00155Y0289*
X00151Y0289*
X00147*
X00143Y0289*
X00138Y0289*
X00134Y02889*
X0013Y02887*
X00126Y02886*
X00122Y02884*
X00118Y02882*
X00115Y0288*
X00111Y02878*
X00108Y02875*
X00105Y02872*
X00102Y02869*
X001Y02865*
X00097Y02862*
X00095Y02858*
X00093Y02854*
X00092Y0285*
X0009Y02846*
X00089Y02842*
X00089Y02838*
X00088Y02834*
X00088Y02829*
X00088Y02825*
X00089Y02821*
X00089Y02817*
X0009Y02813*
X00092Y02809*
X00093Y02805*
X00095Y02801*
X00097Y02797*
X001Y02794*
X00102Y0279*
X00105Y02787*
X00108Y02784*
X00111Y02781*
X00115Y02779*
X00119Y02777*
X00122Y02775*
X00126Y02773*
X0013Y02771*
X00134Y0277*
X00138Y02769*
X00143Y02769*
X00147Y02768*
X00151*
X00155Y02769*
X0016Y02769*
X00164Y0277*
X00168Y02771*
X00172Y02773*
X00176Y02775*
X0018Y02777*
X00183Y02779*
X00187Y02781*
X0019Y02784*
X00193Y02787*
X00196Y0279*
X00198Y02794*
X00201Y02797*
X00203Y02801*
X00205Y02805*
X00206Y02809*
X00208Y02813*
X00209Y02817*
X00209Y02821*
X0021Y02825*
X0021Y02829*
Y03853D02*
D01*
X0021Y03857*
X00209Y03862*
X00209Y03866*
X00208Y0387*
X00206Y03874*
X00205Y03878*
X00203Y03882*
X00201Y03885*
X00198Y03889*
X00196Y03892*
X00193Y03895*
X0019Y03898*
X00187Y03901*
X00183Y03904*
X0018Y03906*
X00176Y03908*
X00172Y0391*
X00168Y03911*
X00164Y03912*
X0016Y03913*
X00155Y03914*
X00151Y03914*
X00147*
X00143Y03914*
X00138Y03913*
X00134Y03912*
X0013Y03911*
X00126Y0391*
X00122Y03908*
X00118Y03906*
X00115Y03904*
X00111Y03901*
X00108Y03898*
X00105Y03895*
X00102Y03892*
X001Y03889*
X00097Y03885*
X00095Y03882*
X00093Y03878*
X00092Y03874*
X0009Y0387*
X00089Y03866*
X00089Y03862*
X00088Y03857*
X00088Y03853*
X00088Y03849*
X00089Y03845*
X00089Y0384*
X0009Y03836*
X00092Y03832*
X00093Y03828*
X00095Y03824*
X00097Y03821*
X001Y03817*
X00102Y03814*
X00105Y03811*
X00108Y03808*
X00111Y03805*
X00115Y03802*
X00119Y038*
X00122Y03798*
X00126Y03796*
X0013Y03795*
X00134Y03794*
X00138Y03793*
X00143Y03792*
X00147Y03792*
X00151*
X00155Y03792*
X0016Y03793*
X00164Y03794*
X00168Y03795*
X00172Y03796*
X00176Y03798*
X0018Y038*
X00183Y03802*
X00187Y03805*
X0019Y03808*
X00193Y03811*
X00196Y03814*
X00198Y03817*
X00201Y03821*
X00203Y03824*
X00205Y03828*
X00206Y03832*
X00208Y03836*
X00209Y0384*
X00209Y03845*
X0021Y03849*
X0021Y03853*
X02592D02*
D01*
X02592Y03857*
X02591Y03862*
X02591Y03866*
X0259Y0387*
X02588Y03874*
X02587Y03878*
X02585Y03882*
X02583Y03885*
X0258Y03889*
X02578Y03892*
X02575Y03895*
X02572Y03898*
X02568Y03901*
X02565Y03904*
X02561Y03906*
X02558Y03908*
X02554Y0391*
X0255Y03911*
X02546Y03912*
X02541Y03913*
X02537Y03914*
X02533Y03914*
X02529*
X02525Y03914*
X0252Y03913*
X02516Y03912*
X02512Y03911*
X02508Y0391*
X02504Y03908*
X025Y03906*
X02497Y03904*
X02493Y03901*
X0249Y03898*
X02487Y03895*
X02484Y03892*
X02482Y03889*
X02479Y03885*
X02477Y03882*
X02475Y03878*
X02474Y03874*
X02472Y0387*
X02471Y03866*
X0247Y03862*
X0247Y03857*
X0247Y03853*
X0247Y03849*
X0247Y03845*
X02471Y0384*
X02472Y03836*
X02474Y03832*
X02475Y03828*
X02477Y03824*
X02479Y03821*
X02482Y03817*
X02484Y03814*
X02487Y03811*
X0249Y03808*
X02493Y03805*
X02497Y03802*
X025Y038*
X02504Y03798*
X02508Y03796*
X02512Y03795*
X02516Y03794*
X0252Y03793*
X02525Y03792*
X02529Y03792*
X02533*
X02537Y03792*
X02541Y03793*
X02546Y03794*
X0255Y03795*
X02554Y03796*
X02558Y03798*
X02561Y038*
X02565Y03802*
X02568Y03805*
X02572Y03808*
X02575Y03811*
X02578Y03814*
X0258Y03817*
X02583Y03821*
X02585Y03824*
X02587Y03828*
X02588Y03832*
X0259Y03836*
X02591Y0384*
X02591Y03845*
X02592Y03849*
X02592Y03853*
Y02829D02*
D01*
X02592Y02834*
X02591Y02838*
X02591Y02842*
X0259Y02846*
X02588Y0285*
X02587Y02854*
X02585Y02858*
X02583Y02862*
X0258Y02865*
X02578Y02869*
X02575Y02872*
X02572Y02875*
X02568Y02878*
X02565Y0288*
X02561Y02882*
X02558Y02884*
X02554Y02886*
X0255Y02887*
X02546Y02889*
X02541Y0289*
X02537Y0289*
X02533Y0289*
X02529*
X02525Y0289*
X0252Y0289*
X02516Y02889*
X02512Y02887*
X02508Y02886*
X02504Y02884*
X025Y02882*
X02497Y0288*
X02493Y02878*
X0249Y02875*
X02487Y02872*
X02484Y02869*
X02482Y02865*
X02479Y02862*
X02477Y02858*
X02475Y02854*
X02474Y0285*
X02472Y02846*
X02471Y02842*
X0247Y02838*
X0247Y02834*
X0247Y02829*
X0247Y02825*
X0247Y02821*
X02471Y02817*
X02472Y02813*
X02474Y02809*
X02475Y02805*
X02477Y02801*
X02479Y02797*
X02482Y02794*
X02484Y0279*
X02487Y02787*
X0249Y02784*
X02493Y02781*
X02497Y02779*
X025Y02777*
X02504Y02775*
X02508Y02773*
X02512Y02771*
X02516Y0277*
X0252Y02769*
X02525Y02769*
X02529Y02768*
X02533*
X02537Y02769*
X02541Y02769*
X02546Y0277*
X0255Y02771*
X02554Y02773*
X02558Y02775*
X02561Y02777*
X02565Y02779*
X02568Y02781*
X02572Y02784*
X02575Y02787*
X02578Y0279*
X0258Y02794*
X02583Y02797*
X02585Y02801*
X02587Y02805*
X02588Y02809*
X0259Y02813*
X02591Y02817*
X02591Y02821*
X02592Y02825*
X02592Y02829*
X03778Y02689D02*
X05778D01*
X03778Y00689D02*
Y02689D01*
Y00689D02*
X05778D01*
Y02689*
X06364Y03351D02*
X06534D01*
X06364Y03131D02*
Y03351D01*
Y03131D02*
X06534D01*
Y03351*
X06931Y02348D02*
Y02874D01*
X06427Y02348D02*
X06931D01*
X06427D02*
Y02874D01*
X06931*
X06067Y01388D02*
Y01914D01*
X06571*
Y01388D02*
Y01914D01*
X06067Y01388D02*
X06571D01*
X00018Y02716D02*
X02662D01*
X00018D02*
Y03966D01*
X02662*
Y02716D02*
Y03966D01*
X02402Y04126D02*
Y04106D01*
Y04116*
X02462*
X02452Y04126*
X03984Y03973D02*
X03964D01*
X03974*
Y03913*
X03984Y03923*
X03543Y02184D02*
X03563D01*
X03553*
Y02244*
X03543Y02234*
X02108Y02409D02*
X02068D01*
X02108Y02449*
Y02459*
X02098Y02469*
X02078*
X02068Y02459*
X01668Y02234D02*
X01678Y02244D01*
X01698*
X01708Y02234*
Y02224*
X01698Y02214*
X01688*
X01698*
X01708Y02204*
Y02194*
X01698Y02184*
X01678*
X01668Y02194*
X02098Y00934D02*
Y00994D01*
X02068Y00964*
X02108*
X03191Y02946D02*
X03201D01*
X03196*
Y02916*
X03191*
X03201*
X03236Y02941D02*
X03231Y02946D01*
X03221*
X03216Y02941*
Y02921*
X03221Y02916*
X03231*
X03236Y02921*
X03246Y02941D02*
X03251Y02946D01*
X03261*
X03266Y02941*
Y02936*
X03256Y02926*
Y02921D02*
Y02916D01*
X00891Y00772D02*
Y00802D01*
X00906*
X00911Y00797*
Y00787*
X00906Y00782*
X00891*
X00901D02*
X00911Y00772D01*
X00921Y00797D02*
X00926Y00802D01*
X00936*
X00941Y00797*
Y00792*
X00936Y00787*
X00931*
X00936*
X00941Y00782*
Y00777*
X00936Y00772*
X00926*
X00921Y00777*
X00971Y00802D02*
X00961Y00797D01*
X00951Y00787*
Y00777*
X00956Y00772*
X00966*
X00971Y00777*
Y00782*
X00966Y00787*
X00951*
X01048Y01218D02*
Y01248D01*
X01063*
X01068Y01243*
Y01233*
X01063Y01228*
X01048*
X01058D02*
X01068Y01218D01*
X01078D02*
X01088D01*
X01083*
Y01248*
X01078Y01243*
X01123Y01248D02*
X01113Y01243D01*
X01103Y01233*
Y01223*
X01108Y01218*
X01118*
X01123Y01223*
Y01228*
X01118Y01233*
X01103*
X01069Y01732D02*
Y01762D01*
X01084*
X01089Y01757*
Y01747*
X01084Y01742*
X01069*
X01079D02*
X01089Y01732D01*
X01099D02*
X01109D01*
X01104*
Y01762*
X01099Y01757*
X01144Y01762D02*
X01124D01*
Y01747*
X01134Y01752*
X01139*
X01144Y01747*
Y01737*
X01139Y01732*
X01129*
X01124Y01737*
X01069Y02269D02*
Y02299D01*
X01084*
X01089Y02294*
Y02284*
X01084Y02279*
X01069*
X01079D02*
X01089Y02269D01*
X01099D02*
X01109D01*
X01104*
Y02299*
X01099Y02294*
X01139Y02269D02*
Y02299D01*
X01124Y02284*
X01144*
X02373Y03008D02*
Y03038D01*
X02388*
X02393Y03033*
Y03023*
X02388Y03018*
X02373*
X02383D02*
X02393Y03008D01*
X02403D02*
X02413D01*
X02408*
Y03038*
X02403Y03033*
X02428Y03038D02*
X02448D01*
Y03033*
X02428Y03013*
Y03008*
X02841Y03381D02*
Y03356D01*
X02846Y03351*
X02856*
X02861Y03356*
Y03381*
X02871Y03376D02*
X02876Y03381D01*
X02886*
X02891Y03376*
Y03371*
X02886Y03366*
X02881*
X02886*
X02891Y03361*
Y03356*
X02886Y03351*
X02876*
X02871Y03356*
X04137Y02522D02*
Y02497D01*
X04142Y02492*
X04152*
X04157Y02497*
Y02522*
X04167Y02492D02*
X04177D01*
X04172*
Y02522*
X04167Y02517*
X04192D02*
X04197Y02522D01*
X04207*
X04212Y02517*
Y02497*
X04207Y02492*
X04197*
X04192Y02497*
Y02517*
X04222Y02492D02*
Y02512D01*
X04232Y02522*
X04242Y02512*
Y02492*
Y02507*
X04222*
X04252Y02522D02*
Y02492D01*
X04272*
X04458Y0391D02*
Y0388D01*
X04473*
X04478Y03885*
Y0389*
X04473Y03895*
X04458*
X04473*
X04478Y039*
Y03905*
X04473Y0391*
X04458*
X04488D02*
X04508D01*
X04498*
Y0388*
X04518D02*
X04528D01*
X04523*
Y0391*
X04518Y03905*
G54D14*
X02869Y03861D02*
D01*
X02869Y03862*
X02869Y03864*
X02869Y03866*
X02868Y03867*
X02868Y03869*
X02867Y03871*
X02866Y03872*
X02866Y03874*
X02865Y03875*
X02863Y03877*
X02862Y03878*
X02861Y03879*
X0286Y0388*
X02858Y03881*
X02857Y03882*
X02855Y03883*
X02854Y03884*
X02852Y03884*
X0285Y03885*
X02849Y03885*
X02847Y03885*
X02845Y03886*
X02843*
X02842Y03885*
X0284Y03885*
X02838Y03885*
X02837Y03884*
X02835Y03884*
X02833Y03883*
X02832Y03882*
X0283Y03881*
X02829Y0388*
X02828Y03879*
X02826Y03878*
X02825Y03877*
X02824Y03875*
X02823Y03874*
X02822Y03872*
X02822Y03871*
X02821Y03869*
X0282Y03867*
X0282Y03866*
X0282Y03864*
X02819Y03862*
X02819Y03861*
X02819Y03859*
X0282Y03857*
X0282Y03855*
X0282Y03854*
X02821Y03852*
X02822Y0385*
X02822Y03849*
X02823Y03847*
X02824Y03846*
X02825Y03845*
X02826Y03843*
X02828Y03842*
X02829Y03841*
X0283Y0384*
X02832Y03839*
X02833Y03838*
X02835Y03837*
X02837Y03837*
X02838Y03836*
X0284Y03836*
X02842Y03836*
X02843Y03836*
X02845*
X02847Y03836*
X02849Y03836*
X0285Y03836*
X02852Y03837*
X02854Y03837*
X02855Y03838*
X02857Y03839*
X02858Y0384*
X0286Y03841*
X02861Y03842*
X02862Y03843*
X02863Y03845*
X02865Y03846*
X02866Y03847*
X02866Y03849*
X02867Y0385*
X02868Y03852*
X02868Y03854*
X02869Y03855*
X02869Y03857*
X02869Y03859*
X02869Y03861*
X02812Y02905D02*
Y03318D01*
X03056Y02905D02*
Y03318D01*
X02812D02*
X03056D01*
X02812Y02905D02*
X03056D01*
X03426Y03679D02*
X03444D01*
X03426D02*
Y03718D01*
X03495Y03679D02*
X03513D01*
Y03718*
X01675Y04013D02*
X01801D01*
X01675Y0421D02*
X01801D01*
Y04013D02*
Y0421D01*
X01675Y04013D02*
Y0421D01*
X0633Y03663D02*
Y03668D01*
X06208Y03663D02*
Y03668D01*
X0633Y03733D02*
Y03738D01*
X06208Y03733D02*
Y03738D01*
Y03663D02*
X0633D01*
X06208Y03738D02*
X0633D01*
X02744Y03903D02*
X02906D01*
X03383D02*
X03544D01*
X03383Y04268D02*
X03544D01*
X02744D02*
X02906D01*
X03544Y03903D02*
Y04268D01*
X02744Y03903D02*
Y04268D01*
X04132Y00857D02*
Y02457D01*
Y00857D02*
X05522D01*
Y02457*
X04132D02*
X05522D01*
X00923Y00732D02*
X00938D01*
X00923Y00704D02*
X00938D01*
X04897Y02703D02*
X04921D01*
X04909Y02691D02*
Y02715D01*
X04584Y02812D02*
X04812D01*
X05006D02*
X05234D01*
Y03957*
X04584D02*
X04812D01*
X05006D02*
X05234D01*
X04584Y02812D02*
Y03957D01*
X00903Y00782D02*
X01186D01*
X00903Y0103D02*
X01186D01*
Y00782D02*
Y00828D01*
X00903Y00782D02*
Y00828D01*
X01186Y00983D02*
Y0103D01*
X00903Y00983D02*
Y0103D01*
X0602Y03663D02*
Y03668D01*
X05898Y03663D02*
Y03668D01*
X0602Y03733D02*
Y03738D01*
X05898Y03733D02*
Y03738D01*
Y03663D02*
X0602D01*
X05898Y03738D02*
X0602D01*
X06213Y03603D02*
X06335D01*
X06213Y03528D02*
X06335D01*
X06213Y03598D02*
Y03603D01*
X06335Y03598D02*
Y03603D01*
X06213Y03528D02*
Y03533D01*
X06335Y03528D02*
Y03533D01*
X02791Y03679D02*
X02809D01*
X02791D02*
Y03718D01*
X0286Y03679D02*
X02878D01*
Y03718*
X02676Y03679D02*
X02694D01*
X02676D02*
Y03718D01*
X02745Y03679D02*
X02763D01*
Y03718*
X03201Y03679D02*
X03219D01*
X03201D02*
Y03718D01*
X0327Y03679D02*
X03288D01*
Y03718*
X00903Y02033D02*
Y0208D01*
X01186Y02033D02*
Y0208D01*
X00903Y01832D02*
Y01878D01*
X01186Y01832D02*
Y01878D01*
X00903Y0208D02*
X01186D01*
X00903Y01832D02*
X01186D01*
X00903Y02558D02*
Y02605D01*
X01186Y02558D02*
Y02605D01*
X00903Y02357D02*
Y02403D01*
X01186Y02357D02*
Y02403D01*
X00903Y02605D02*
X01186D01*
X00903Y02357D02*
X01186D01*
X00903Y01307D02*
X01186D01*
X00903Y01555D02*
X01186D01*
Y01307D02*
Y01353D01*
X00903Y01307D02*
Y01353D01*
X01186Y01508D02*
Y01555D01*
X00903Y01508D02*
Y01555D01*
X03816Y03672D02*
X03942D01*
X03816Y03869D02*
X03942D01*
Y03672D02*
Y03869D01*
X03816Y03672D02*
Y03869D01*
X01332Y04104D02*
Y0412D01*
X0136Y04104D02*
Y0412D01*
Y04D02*
Y04015D01*
X01332Y04D02*
Y04015D01*
X02137Y04037D02*
Y04053D01*
X02165Y04037D02*
Y04053D01*
X02198Y04037D02*
Y04053D01*
X02226Y04037D02*
Y04053D01*
X02374Y02921D02*
Y02937D01*
X02401Y02921D02*
Y02937D01*
X0093Y02298D02*
X00945D01*
X0093Y0227D02*
X00945D01*
X00922Y0176D02*
X00937D01*
X00922Y01733D02*
X00937D01*
X00926Y01238D02*
X00941D01*
X00926Y0121D02*
X00941D01*
G54D15*
X06127Y03741D02*
D01*
X06127Y03741*
X06127Y03742*
X06127Y03742*
X06127Y03743*
X06127Y03743*
X06127Y03744*
X06126Y03744*
X06126Y03745*
X06126Y03745*
X06125Y03746*
X06125Y03746*
X06125Y03746*
X06124Y03747*
X06124Y03747*
X06123Y03747*
X06123Y03748*
X06122Y03748*
X06122Y03748*
X06121Y03748*
X06121Y03748*
X0612Y03748*
X0612Y03748*
X06119*
X06119Y03748*
X06118Y03748*
X06117Y03748*
X06117Y03748*
X06116Y03748*
X06116Y03748*
X06115Y03747*
X06115Y03747*
X06115Y03747*
X06114Y03746*
X06114Y03746*
X06113Y03746*
X06113Y03745*
X06113Y03745*
X06112Y03744*
X06112Y03744*
X06112Y03743*
X06112Y03743*
X06112Y03742*
X06112Y03742*
X06111Y03741*
X06111Y03741*
X06111Y0374*
X06112Y0374*
X06112Y03739*
X06112Y03738*
X06112Y03738*
X06112Y03737*
X06112Y03737*
X06113Y03736*
X06113Y03736*
X06113Y03736*
X06114Y03735*
X06114Y03735*
X06115Y03734*
X06115Y03734*
X06115Y03734*
X06116Y03734*
X06116Y03733*
X06117Y03733*
X06117Y03733*
X06118Y03733*
X06119Y03733*
X06119Y03733*
X0612*
X0612Y03733*
X06121Y03733*
X06121Y03733*
X06122Y03733*
X06122Y03733*
X06123Y03734*
X06123Y03734*
X06124Y03734*
X06124Y03734*
X06125Y03735*
X06125Y03735*
X06125Y03736*
X06126Y03736*
X06126Y03736*
X06126Y03737*
X06127Y03737*
X06127Y03738*
X06127Y03738*
X06127Y03739*
X06127Y0374*
X06127Y0374*
X06127Y03741*
G54D16*
X03441Y02088D02*
D01*
X03441Y02088*
X03441Y02089*
X03441Y02089*
X03441Y0209*
X03441Y02091*
X0344Y02091*
X0344Y02092*
X0344Y02092*
X0344Y02092*
X03439Y02093*
X03439Y02093*
X03439Y02094*
X03438Y02094*
X03438Y02094*
X03437Y02095*
X03437Y02095*
X03436Y02095*
X03436Y02095*
X03435Y02095*
X03435Y02096*
X03434Y02096*
X03434Y02096*
X03433*
X03432Y02096*
X03432Y02096*
X03431Y02095*
X03431Y02095*
X0343Y02095*
X0343Y02095*
X03429Y02095*
X03429Y02094*
X03428Y02094*
X03428Y02094*
X03428Y02093*
X03427Y02093*
X03427Y02092*
X03427Y02092*
X03426Y02092*
X03426Y02091*
X03426Y02091*
X03426Y0209*
X03426Y02089*
X03425Y02089*
X03425Y02088*
X03425Y02088*
X03425Y02087*
X03425Y02087*
X03426Y02086*
X03426Y02086*
X03426Y02085*
X03426Y02085*
X03426Y02084*
X03427Y02084*
X03427Y02083*
X03427Y02083*
X03428Y02082*
X03428Y02082*
X03428Y02082*
X03429Y02081*
X03429Y02081*
X0343Y02081*
X0343Y02081*
X03431Y0208*
X03431Y0208*
X03432Y0208*
X03432Y0208*
X03433Y0208*
X03434*
X03434Y0208*
X03435Y0208*
X03435Y0208*
X03436Y0208*
X03436Y02081*
X03437Y02081*
X03437Y02081*
X03438Y02081*
X03438Y02082*
X03439Y02082*
X03439Y02082*
X03439Y02083*
X0344Y02083*
X0344Y02084*
X0344Y02084*
X0344Y02085*
X03441Y02085*
X03441Y02086*
X03441Y02086*
X03441Y02087*
X03441Y02087*
X03441Y02088*
X02219Y023D02*
D01*
X02219Y02301*
X02219Y02301*
X02219Y02302*
X02219Y02302*
X02219Y02303*
X02219Y02303*
X02218Y02304*
X02218Y02304*
X02218Y02305*
X02218Y02305*
X02217Y02306*
X02217Y02306*
X02216Y02306*
X02216Y02307*
X02215Y02307*
X02215Y02307*
X02214Y02307*
X02214Y02308*
X02213Y02308*
X02213Y02308*
X02212Y02308*
X02212Y02308*
X02211*
X02211Y02308*
X0221Y02308*
X0221Y02308*
X02209Y02308*
X02209Y02307*
X02208Y02307*
X02208Y02307*
X02207Y02307*
X02207Y02306*
X02206Y02306*
X02206Y02306*
X02205Y02305*
X02205Y02305*
X02205Y02304*
X02205Y02304*
X02204Y02303*
X02204Y02303*
X02204Y02302*
X02204Y02302*
X02204Y02301*
X02204Y02301*
X02204Y023*
X02204Y02299*
X02204Y02299*
X02204Y02298*
X02204Y02298*
X02204Y02297*
X02204Y02297*
X02205Y02296*
X02205Y02296*
X02205Y02295*
X02205Y02295*
X02206Y02295*
X02206Y02294*
X02207Y02294*
X02207Y02293*
X02208Y02293*
X02208Y02293*
X02209Y02293*
X02209Y02293*
X0221Y02292*
X0221Y02292*
X02211Y02292*
X02211Y02292*
X02212*
X02212Y02292*
X02213Y02292*
X02213Y02292*
X02214Y02293*
X02214Y02293*
X02215Y02293*
X02215Y02293*
X02216Y02293*
X02216Y02294*
X02217Y02294*
X02217Y02295*
X02218Y02295*
X02218Y02295*
X02218Y02296*
X02218Y02296*
X02219Y02297*
X02219Y02297*
X02219Y02298*
X02219Y02298*
X02219Y02299*
X02219Y02299*
X02219Y023*
X01842Y01318D02*
D01*
X01842Y01319*
X01842Y01319*
X01842Y0132*
X01842Y0132*
X01842Y01321*
X01842Y01321*
X01841Y01322*
X01841Y01322*
X01841Y01323*
X0184Y01323*
X0184Y01324*
X0184Y01324*
X01839Y01324*
X01839Y01325*
X01838Y01325*
X01838Y01325*
X01837Y01325*
X01837Y01326*
X01836Y01326*
X01836Y01326*
X01835Y01326*
X01835Y01326*
X01834*
X01834Y01326*
X01833Y01326*
X01832Y01326*
X01832Y01326*
X01831Y01325*
X01831Y01325*
X0183Y01325*
X0183Y01325*
X01829Y01324*
X01829Y01324*
X01829Y01324*
X01828Y01323*
X01828Y01323*
X01828Y01322*
X01827Y01322*
X01827Y01321*
X01827Y01321*
X01827Y0132*
X01827Y0132*
X01827Y01319*
X01826Y01319*
X01826Y01318*
X01826Y01318*
X01827Y01317*
X01827Y01317*
X01827Y01316*
X01827Y01315*
X01827Y01315*
X01827Y01314*
X01828Y01314*
X01828Y01314*
X01828Y01313*
X01829Y01313*
X01829Y01312*
X01829Y01312*
X0183Y01312*
X0183Y01311*
X01831Y01311*
X01831Y01311*
X01832Y01311*
X01832Y01311*
X01833Y0131*
X01834Y0131*
X01834Y0131*
X01835*
X01835Y0131*
X01836Y0131*
X01836Y01311*
X01837Y01311*
X01837Y01311*
X01838Y01311*
X01838Y01311*
X01839Y01312*
X01839Y01312*
X0184Y01312*
X0184Y01313*
X0184Y01313*
X01841Y01314*
X01841Y01314*
X01841Y01314*
X01842Y01315*
X01842Y01315*
X01842Y01316*
X01842Y01317*
X01842Y01317*
X01842Y01318*
X01842Y01318*
X02989Y01096D02*
D01*
X02989Y01097*
X02989Y01097*
X02989Y01098*
X02989Y01098*
X02989Y01099*
X02988Y01099*
X02988Y011*
X02988Y011*
X02988Y01101*
X02987Y01101*
X02987Y01102*
X02986Y01102*
X02986Y01102*
X02986Y01103*
X02985Y01103*
X02985Y01103*
X02984Y01103*
X02984Y01104*
X02983Y01104*
X02983Y01104*
X02982Y01104*
X02981Y01104*
X02981*
X0298Y01104*
X0298Y01104*
X02979Y01104*
X02979Y01104*
X02978Y01103*
X02978Y01103*
X02977Y01103*
X02977Y01103*
X02976Y01102*
X02976Y01102*
X02976Y01102*
X02975Y01101*
X02975Y01101*
X02975Y011*
X02974Y011*
X02974Y01099*
X02974Y01099*
X02974Y01098*
X02973Y01098*
X02973Y01097*
X02973Y01097*
X02973Y01096*
X02973Y01096*
X02973Y01095*
X02973Y01094*
X02974Y01094*
X02974Y01093*
X02974Y01093*
X02974Y01092*
X02975Y01092*
X02975Y01091*
X02975Y01091*
X02976Y01091*
X02976Y0109*
X02976Y0109*
X02977Y0109*
X02977Y01089*
X02978Y01089*
X02978Y01089*
X02979Y01089*
X02979Y01088*
X0298Y01088*
X0298Y01088*
X02981Y01088*
X02981*
X02982Y01088*
X02983Y01088*
X02983Y01088*
X02984Y01089*
X02984Y01089*
X02985Y01089*
X02985Y01089*
X02986Y0109*
X02986Y0109*
X02986Y0109*
X02987Y01091*
X02987Y01091*
X02988Y01091*
X02988Y01092*
X02988Y01092*
X02988Y01093*
X02989Y01093*
X02989Y01094*
X02989Y01094*
X02989Y01095*
X02989Y01096*
X02989Y01096*
G54D17*
X02172Y0416D02*
Y04235D01*
X02492Y0416D02*
Y04235D01*
X03684Y04098D02*
Y04173D01*
X04059Y04098D02*
Y04173D01*
X06684Y03181D02*
Y03281D01*
X06779Y03306D02*
X06889D01*
X06779Y03156D02*
X06889D01*
X07009Y03166D02*
Y03296D01*
X06659Y03156D02*
Y03306D01*
X06674*
X06659Y03156D02*
X06674D01*
X07009D02*
Y03166D01*
X06994Y03156D02*
X07009D01*
Y03296D02*
Y03306D01*
X06994D02*
X07009D01*
X03319Y03706D02*
X03379D01*
X03504Y02777D02*
Y02816D01*
X05396Y03982D02*
Y04224D01*
X05831*
X05396Y03464D02*
Y03982D01*
Y03464D02*
X05831D01*
Y04224*
X06062Y03536D02*
Y03575D01*
X04377Y02786D02*
Y02846D01*
X04301Y02786D02*
Y02846D01*
X04067Y03036D02*
Y03086D01*
X04011Y03036D02*
Y03086D01*
X01993Y04307D02*
X02093D01*
X01993Y04007D02*
Y04307D01*
Y04007D02*
X02093D01*
Y04307*
X05746Y03323D02*
X05806D01*
X05746Y03399D02*
X05806D01*
X06497Y02246D02*
Y02296D01*
X06441Y02246D02*
Y02296D01*
X06547Y01961D02*
Y02011D01*
X06491Y01961D02*
Y02011D01*
X06372Y02116D02*
Y02176D01*
X06296Y02116D02*
Y02176D01*
X06621Y02101D02*
Y02161D01*
X06697Y02101D02*
Y02161D01*
X06215Y02761D02*
Y02821D01*
X06291Y02761D02*
Y02821D01*
X06334Y02761D02*
Y02821D01*
X0641Y02761D02*
Y02821D01*
X06634Y01383D02*
X06694D01*
X06634Y01459D02*
X06694D01*
X06634Y01493D02*
X06694D01*
X06634Y01569D02*
X06694D01*
X06849Y02124D02*
X06899D01*
X06849Y02068D02*
X06899D01*
X06099Y02143D02*
X06149D01*
X06099Y02199D02*
X06149D01*
X04142Y03776D02*
Y03836D01*
X04066Y03776D02*
Y03836D01*
X04222Y03781D02*
Y03831D01*
X04166Y03781D02*
Y03831D01*
X06444Y03033D02*
X06504D01*
X06444Y03109D02*
X06504D01*
X02171Y03651D02*
Y03711D01*
X02247Y03651D02*
Y03711D01*
X02677Y03541D02*
Y03601D01*
X02601Y03541D02*
Y03601D01*
X03664Y00764D02*
X03724D01*
X03664Y00688D02*
X03724D01*
X03655Y03123D02*
Y03183D01*
X03731Y03123D02*
Y03183D01*
X03716Y03273D02*
Y03323D01*
X0366Y03273D02*
Y03323D01*
X04177Y03583D02*
Y03623D01*
X0673Y02116D02*
X06769D01*
X06215Y02156D02*
X06254D01*
X06869Y01796D02*
Y01835D01*
X06754Y01796D02*
Y01835D01*
X06339Y02431D02*
Y0247D01*
X0699Y01911D02*
X07029D01*
X05985Y02366D02*
X06024D01*
X02914Y03706D02*
X02974D01*
X03014D02*
X03074D01*
X03114D02*
X03174D01*
X02127Y02652D02*
X02166D01*
X04139Y03681D02*
Y0372D01*
X00619Y04066D02*
X00658D01*
X0082D02*
X0086D01*
X01022D02*
X01061D01*
X01224D02*
X01263D01*
X04679Y04186D02*
Y04225D01*
X05239Y04186D02*
Y04225D01*
X04679Y04101D02*
Y0414D01*
X05239Y04106D02*
Y04145D01*
X06103Y02461D02*
X06142D01*
X01914Y04102D02*
X01953D01*
X0167Y04245D02*
X0172D01*
X0167Y04301D02*
X0172D01*
X01807Y04238D02*
X01867D01*
X01807Y04314D02*
X01867D01*
X06632Y03271D02*
Y03321D01*
X06576Y03271D02*
Y03321D01*
Y03136D02*
Y03186D01*
X06632Y03136D02*
Y03186D01*
X04214Y03284D02*
X04274D01*
X04214Y03208D02*
X04274D01*
X04102Y02786D02*
Y02846D01*
X04026Y02786D02*
Y02846D01*
X03997Y02786D02*
Y02846D01*
X03921Y02786D02*
Y02846D01*
X04272Y02786D02*
Y02846D01*
X04196Y02786D02*
Y02846D01*
X01407Y04303D02*
X01507D01*
X01407Y04003D02*
Y04303D01*
Y04003D02*
X01507D01*
Y04303*
G54D18*
X06176Y02217D02*
X06388D01*
X06176Y02414D02*
X06333D01*
X066Y02054D02*
X06813D01*
X06656Y01857D02*
X06813D01*
G54D19*
X03274Y03438D02*
X03313D01*
X03274Y03399D02*
Y03438D01*
Y03162D02*
Y03202D01*
X03589Y03162D02*
X03628D01*
Y03202*
Y03326D02*
Y03438D01*
X03508D02*
X03628D01*
X03274Y03162D02*
X03313D01*
X03404Y03029D02*
Y03092D01*
X03458*
X03544D02*
X03564D01*
Y03072D02*
Y03092D01*
Y02852D02*
Y02872D01*
X03544Y02852D02*
X03564D01*
X03404D02*
X03424D01*
X03404D02*
Y02872D01*
X04934Y04251D02*
Y04261D01*
X05114*
Y04251D02*
Y04261D01*
Y04151D02*
Y04161D01*
X04934Y04151D02*
X05114D01*
X04934D02*
Y04161D01*
X05909Y03792D02*
X06019D01*
X05909Y04038D02*
Y04205D01*
X06224Y03792D02*
X06309D01*
X05909D02*
Y03837D01*
X06309Y03792D02*
Y04205D01*
X05909D02*
X06309D01*
X06444Y03529D02*
Y04356D01*
Y03529D02*
X07003D01*
Y03572D02*
Y04356D01*
X04409Y04251D02*
Y04261D01*
X04589*
Y04251D02*
Y04261D01*
Y04151D02*
Y04161D01*
X04409Y04151D02*
X04589D01*
X04409D02*
Y04161D01*
G54D20*
X00379Y00726D02*
Y00806D01*
X00099Y00726D02*
X00379D01*
Y01006D02*
Y01086D01*
X00099D02*
X00379D01*
X00069Y00726D02*
X00099D01*
X00029Y00766D02*
X00069Y00726D01*
Y01086D02*
X00099D01*
X00029Y01046D02*
X00069Y01086D01*
X00379Y02301D02*
Y02381D01*
X00099Y02301D02*
X00379D01*
Y02581D02*
Y02661D01*
X00099D02*
X00379D01*
X00069Y02301D02*
X00099D01*
X00029Y02341D02*
X00069Y02301D01*
Y02661D02*
X00099D01*
X00029Y02621D02*
X00069Y02661D01*
X00379Y01776D02*
Y01856D01*
X00099Y01776D02*
X00379D01*
Y02056D02*
Y02136D01*
X00099D02*
X00379D01*
X00069Y01776D02*
X00099D01*
X00029Y01816D02*
X00069Y01776D01*
Y02136D02*
X00099D01*
X00029Y02096D02*
X00069Y02136D01*
X00379Y01251D02*
Y01331D01*
X00099Y01251D02*
X00379D01*
Y01531D02*
Y01611D01*
X00099D02*
X00379D01*
X00069Y01251D02*
X00099D01*
X00029Y01291D02*
X00069Y01251D01*
Y01611D02*
X00099D01*
X00029Y01571D02*
X00069Y01611D01*
G54D21*
X0155Y00815D02*
Y02587D01*
X03716Y00815D02*
Y02587D01*
X0155Y00815D02*
X03716D01*
X0155Y02587D02*
X03716D01*
G54D22*
X03493Y01282D02*
Y01308D01*
Y01282D02*
X03516D01*
Y0126D02*
Y01282D01*
Y0126D02*
X03626D01*
Y01282*
X0365*
Y01308*
X03493Y02098D02*
Y02124D01*
X03516*
Y02146*
X03626*
Y02124D02*
Y02146D01*
Y02124D02*
X0365D01*
Y02098D02*
Y02124D01*
X02175Y02517D02*
X02201D01*
X02175Y02493D02*
Y02517D01*
X02153Y02493D02*
X02175D01*
X02153Y02383D02*
Y02493D01*
Y02383D02*
X02175D01*
Y02359D02*
Y02383D01*
Y02359D02*
X02201D01*
X02991Y02517D02*
X03018D01*
Y02493D02*
Y02517D01*
Y02493D02*
X03039D01*
Y02383D02*
Y02493D01*
X03018Y02383D02*
X03039D01*
X03018Y02359D02*
Y02383D01*
X02991Y02359D02*
X03018D01*
X01775Y02098D02*
Y02124D01*
X01751D02*
X01775D01*
X01751D02*
Y02146D01*
X01641D02*
X01751D01*
X01641Y02124D02*
Y02146D01*
X01618Y02124D02*
X01641D01*
X01618Y02098D02*
Y02124D01*
X01775Y01282D02*
Y01308D01*
X01751Y01282D02*
X01775D01*
X01751Y0126D02*
Y01282D01*
X01641Y0126D02*
X01751D01*
X01641D02*
Y01282D01*
X01618D02*
X01641D01*
X01618D02*
Y01308D01*
X02175Y01037D02*
X02201D01*
X02175Y01013D02*
Y01037D01*
X02153Y01013D02*
X02175D01*
X02153Y00903D02*
Y01013D01*
Y00903D02*
X02175D01*
Y00879D02*
Y00903D01*
Y00879D02*
X02201D01*
X02991Y01037D02*
X03018D01*
Y01013D02*
Y01037D01*
Y01013D02*
X03039D01*
Y00903D02*
Y01013D01*
X03018Y00903D02*
X03039D01*
X03018Y00879D02*
Y00903D01*
X02991Y00879D02*
X03018D01*
G54D23*
X07003Y03529D02*
Y03572D01*
G54D24*
X01953Y04005D02*
Y03995D01*
Y04*
X01978*
X01983Y03995*
Y0399*
X01978Y03985*
X01983Y04015D02*
X01953D01*
Y0403*
X01958Y04035*
X01968*
X01973Y0403*
Y04015*
X01983Y04065D02*
Y04045D01*
X01963Y04065*
X01958*
X01953Y0406*
Y0405*
X01958Y04045*
X01345Y04326D02*
X01335D01*
X0134*
Y04301*
X01335Y04296*
X0133*
X01325Y04301*
X01355Y04296D02*
Y04326D01*
X0137*
X01375Y04321*
Y04311*
X0137Y04306*
X01355*
X01385Y04296D02*
X01395D01*
X0139*
Y04326*
X01385Y04321*
X04338Y02914D02*
X04333Y02909D01*
Y02899*
X04338Y02894*
X04358*
X04363Y02899*
Y02909*
X04358Y02914*
X04333Y02924D02*
Y02944D01*
X04338*
X04358Y02924*
X04363*
Y02974D02*
Y02954D01*
X04343Y02974*
X04338*
X04333Y02969*
Y02959*
X04338Y02954*
X04235Y02915D02*
X0423Y0291D01*
Y029*
X04235Y02895*
X04255*
X0426Y029*
Y0291*
X04255Y02915*
X0423Y02925D02*
Y02945D01*
X04235*
X04255Y02925*
X0426*
X04235Y02955D02*
X0423Y0296D01*
Y0297*
X04235Y02975*
X0424*
X04245Y0297*
Y02965*
Y0297*
X0425Y02975*
X04255*
X0426Y0297*
Y0296*
X04255Y02955*
X03787Y02818D02*
X03782Y02823D01*
X03772*
X03767Y02818*
Y02798*
X03772Y02793*
X03782*
X03787Y02798*
X03797Y02823D02*
X03817D01*
Y02818*
X03797Y02798*
Y02793*
X03842D02*
Y02823D01*
X03827Y02808*
X03847*
X04001Y02936D02*
X03996Y02941D01*
X03986*
X03981Y02936*
Y02916*
X03986Y02911*
X03996*
X04001Y02916*
X04011Y02941D02*
X04031D01*
Y02936*
X04011Y02916*
Y02911*
X04061Y02941D02*
X04041D01*
Y02926*
X04051Y02931*
X04056*
X04061Y02926*
Y02916*
X04056Y02911*
X04046*
X04041Y02916*
X03957Y03208D02*
X03952Y03203D01*
Y03193*
X03957Y03188*
X03977*
X03982Y03193*
Y03203*
X03977Y03208*
X03952Y03218D02*
Y03238D01*
X03957*
X03977Y03218*
X03982*
X03952Y03268D02*
X03957Y03258D01*
X03967Y03248*
X03977*
X03982Y03253*
Y03263*
X03977Y03268*
X03972*
X03967Y03263*
Y03248*
X04011Y03208D02*
X04006Y03203D01*
Y03193*
X04011Y03188*
X04031*
X04036Y03193*
Y03203*
X04031Y03208*
X04006Y03218D02*
Y03238D01*
X04011*
X04031Y03218*
X04036*
X04006Y03248D02*
Y03268D01*
X04011*
X04031Y03248*
X04036*
X04069Y03207D02*
X04064Y03202D01*
Y03192*
X04069Y03187*
X04089*
X04094Y03192*
Y03202*
X04089Y03207*
X04064Y03217D02*
Y03237D01*
X04069*
X04089Y03217*
X04094*
X04069Y03247D02*
X04064Y03252D01*
Y03262*
X04069Y03267*
X04074*
X04079Y03262*
X04084Y03267*
X04089*
X04094Y03262*
Y03252*
X04089Y03247*
X04084*
X04079Y03252*
X04074Y03247*
X04069*
X04079Y03252D02*
Y03262D01*
X04125Y03207D02*
X0412Y03202D01*
Y03192*
X04125Y03187*
X04145*
X0415Y03192*
Y03202*
X04145Y03207*
X0412Y03217D02*
Y03237D01*
X04125*
X04145Y03217*
X0415*
X04145Y03247D02*
X0415Y03252D01*
Y03262*
X04145Y03267*
X04125*
X0412Y03262*
Y03252*
X04125Y03247*
X0413*
X04135Y03252*
Y03267*
X04339Y0323D02*
X04334Y03225D01*
Y03215*
X04339Y0321*
X04359*
X04364Y03215*
Y03225*
X04359Y0323*
X04339Y0324D02*
X04334Y03245D01*
Y03255*
X04339Y0326*
X04344*
X04349Y03255*
X04354Y0326*
X04359*
X04364Y03255*
Y03245*
X04359Y0324*
X04354*
X04349Y03245*
X04344Y0324*
X04339*
X04349Y03245D02*
Y03255D01*
X04339Y0327D02*
X04334Y03275D01*
Y03285*
X04339Y0329*
X04359*
X04364Y03285*
Y03275*
X04359Y0327*
X04339*
X04389Y0323D02*
X04384Y03225D01*
Y03215*
X04389Y0321*
X04409*
X04414Y03215*
Y03225*
X04409Y0323*
X04389Y0324D02*
X04384Y03245D01*
Y03255*
X04389Y0326*
X04394*
X04399Y03255*
X04404Y0326*
X04409*
X04414Y03255*
Y03245*
X04409Y0324*
X04404*
X04399Y03245*
X04394Y0324*
X04389*
X04399Y03245D02*
Y03255D01*
X04414Y0327D02*
Y0328D01*
Y03275*
X04384*
X04389Y0327*
X04438Y03225D02*
X04433Y0322D01*
Y0321*
X04438Y03205*
X04458*
X04463Y0321*
Y0322*
X04458Y03225*
X04438Y03235D02*
X04433Y0324D01*
Y0325*
X04438Y03255*
X04443*
X04448Y0325*
X04453Y03255*
X04458*
X04463Y0325*
Y0324*
X04458Y03235*
X04453*
X04448Y0324*
X04443Y03235*
X04438*
X04448Y0324D02*
Y0325D01*
X04463Y03285D02*
Y03265D01*
X04443Y03285*
X04438*
X04433Y0328*
Y0327*
X04438Y03265*
X04487Y03185D02*
X04482Y0318D01*
Y0317*
X04487Y03165*
X04507*
X04512Y0317*
Y0318*
X04507Y03185*
X04487Y03195D02*
X04482Y032D01*
Y0321*
X04487Y03215*
X04492*
X04497Y0321*
X04502Y03215*
X04507*
X04512Y0321*
Y032*
X04507Y03195*
X04502*
X04497Y032*
X04492Y03195*
X04487*
X04497Y032D02*
Y0321D01*
X04487Y03225D02*
X04482Y0323D01*
Y0324*
X04487Y03245*
X04492*
X04497Y0324*
Y03235*
Y0324*
X04502Y03245*
X04507*
X04512Y0324*
Y0323*
X04507Y03225*
X042Y03341D02*
X04195Y03346D01*
X04185*
X0418Y03341*
Y03321*
X04185Y03316*
X04195*
X042Y03321*
X0421Y03341D02*
X04215Y03346D01*
X04225*
X0423Y03341*
Y03336*
X04225Y03331*
X0423Y03326*
Y03321*
X04225Y03316*
X04215*
X0421Y03321*
Y03326*
X04215Y03331*
X0421Y03336*
Y03341*
X04215Y03331D02*
X04225D01*
X04255Y03316D02*
Y03346D01*
X0424Y03331*
X0426*
X06654Y03076D02*
X06649Y03081D01*
X06639*
X06634Y03076*
Y03056*
X06639Y03051*
X06649*
X06654Y03056*
X06664Y03076D02*
X06669Y03081D01*
X06679*
X06684Y03076*
Y03071*
X06679Y03066*
X06684Y03061*
Y03056*
X06679Y03051*
X06669*
X06664Y03056*
Y03061*
X06669Y03066*
X06664Y03071*
Y03076*
X06669Y03066D02*
X06679D01*
X06714Y03081D02*
X06694D01*
Y03066*
X06704Y03071*
X06709*
X06714Y03066*
Y03056*
X06709Y03051*
X06699*
X06694Y03056*
X06605Y03399D02*
X066Y03404D01*
X0659*
X06585Y03399*
Y03379*
X0659Y03374*
X066*
X06605Y03379*
X06615Y03399D02*
X0662Y03404D01*
X0663*
X06635Y03399*
Y03394*
X0663Y03389*
X06635Y03384*
Y03379*
X0663Y03374*
X0662*
X06615Y03379*
Y03384*
X0662Y03389*
X06615Y03394*
Y03399*
X0662Y03389D02*
X0663D01*
X06665Y03404D02*
X06655Y03399D01*
X06645Y03389*
Y03379*
X0665Y03374*
X0666*
X06665Y03379*
Y03384*
X0666Y03389*
X06645*
X0194Y04243D02*
X01935Y04238D01*
Y04228*
X0194Y04223*
X0196*
X01965Y04228*
Y04238*
X0196Y04243*
Y04253D02*
X01965Y04258D01*
Y04268*
X0196Y04273*
X0194*
X01935Y04268*
Y04258*
X0194Y04253*
X01945*
X0195Y04258*
Y04273*
X01965Y04283D02*
Y04293D01*
Y04288*
X01935*
X0194Y04283*
X01525Y04279D02*
X0152Y04284D01*
X0151*
X01505Y04279*
Y04259*
X0151Y04254*
X0152*
X01525Y04259*
X01535D02*
X0154Y04254D01*
X0155*
X01555Y04259*
Y04279*
X0155Y04284*
X0154*
X01535Y04279*
Y04274*
X0154Y04269*
X01555*
X01585Y04254D02*
X01565D01*
X01585Y04274*
Y04279*
X0158Y04284*
X0157*
X01565Y04279*
X03446Y02694D02*
Y02724D01*
X03461*
X03466Y02719*
Y02709*
X03461Y02704*
X03446*
X03456D02*
X03466Y02694D01*
X03491D02*
Y02724D01*
X03476Y02709*
X03496*
X03526Y02694D02*
X03506D01*
X03526Y02714*
Y02719*
X03521Y02724*
X03511*
X03506Y02719*
X01895Y04167D02*
Y04197D01*
X0191*
X01915Y04192*
Y04182*
X0191Y04177*
X01895*
X01905D02*
X01915Y04167D01*
X0194D02*
Y04197D01*
X01925Y04182*
X01945*
X01955Y04192D02*
X0196Y04197D01*
X0197*
X01975Y04192*
Y04187*
X0197Y04182*
X01965*
X0197*
X01975Y04177*
Y04172*
X0197Y04167*
X0196*
X01955Y04172*
X01541Y04025D02*
X01566D01*
X01571Y0403*
Y0404*
X01566Y04045*
X01541*
X01571Y04055D02*
Y04065D01*
Y0406*
X01541*
X01546Y04055*
X01541Y041D02*
X01546Y0409D01*
X01556Y0408*
X01566*
X01571Y04085*
Y04095*
X01566Y041*
X01561*
X01556Y04095*
Y0408*
X02535Y04188D02*
X02525D01*
X0253*
Y04163*
X02525Y04158*
X0252*
X02515Y04163*
X0256Y04158D02*
Y04188D01*
X02545Y04173*
X02565*
X06134Y02525D02*
X06104D01*
Y0254*
X06109Y02545*
X06119*
X06124Y0254*
Y02525*
Y02535D02*
X06134Y02545D01*
X06104Y02575D02*
Y02555D01*
X06119*
X06114Y02565*
Y0257*
X06119Y02575*
X06129*
X06134Y0257*
Y0256*
X06129Y02555*
X06951Y03391D02*
X06971Y03361D01*
Y03391D02*
X06951Y03361D01*
X06981D02*
X06991D01*
X06986*
Y03391*
X06981Y03386*
X03588Y02889D02*
Y02864D01*
X03593Y02859*
X03603*
X03608Y02864*
Y02889*
X03618Y02859D02*
X03628D01*
X03623*
Y02889*
X03618Y02884*
X03643D02*
X03648Y02889D01*
X03658*
X03663Y02884*
Y02879*
X03658Y02874*
X03653*
X03658*
X03663Y02869*
Y02864*
X03658Y02859*
X03648*
X03643Y02864*
X03159Y0342D02*
Y03395D01*
X03164Y0339*
X03174*
X03179Y03395*
Y0342*
X03189Y0339D02*
X03199D01*
X03194*
Y0342*
X03189Y03415*
X03214Y0339D02*
X03224D01*
X03219*
Y0342*
X03214Y03415*
X05652Y02744D02*
Y02719D01*
X05657Y02714*
X05667*
X05672Y02719*
Y02744*
X05682Y02714D02*
X05692D01*
X05687*
Y02744*
X05682Y02739*
X05707D02*
X05712Y02744D01*
X05722*
X05727Y02739*
Y02719*
X05722Y02714*
X05712*
X05707Y02719*
Y02739*
X02388Y03741D02*
Y03716D01*
X02393Y03711*
X02403*
X02408Y03716*
Y03741*
X02418Y03716D02*
X02423Y03711D01*
X02433*
X02438Y03716*
Y03736*
X02433Y03741*
X02423*
X02418Y03736*
Y03731*
X02423Y03726*
X02438*
X06368Y03415D02*
Y0339D01*
X06373Y03385*
X06383*
X06388Y0339*
Y03415*
X06398Y0341D02*
X06403Y03415D01*
X06413*
X06418Y0341*
Y03405*
X06413Y034*
X06418Y03395*
Y0339*
X06413Y03385*
X06403*
X06398Y0339*
Y03395*
X06403Y034*
X06398Y03405*
Y0341*
X06403Y034D02*
X06413D01*
X03841Y03633D02*
Y03608D01*
X03846Y03603*
X03856*
X03861Y03608*
Y03633*
X03891D02*
X03881Y03628D01*
X03871Y03618*
Y03608*
X03876Y03603*
X03886*
X03891Y03608*
Y03613*
X03886Y03618*
X03871*
X02629Y04251D02*
Y04226D01*
X02634Y04221*
X02644*
X02649Y04226*
Y04251*
X02679D02*
X02659D01*
Y04236*
X02669Y04241*
X02674*
X02679Y04236*
Y04226*
X02674Y04221*
X02664*
X02659Y04226*
X06013Y0226D02*
Y02235D01*
X06018Y0223*
X06028*
X06033Y02235*
Y0226*
X06063Y0223D02*
X06043D01*
X06063Y0225*
Y02255*
X06058Y0226*
X06048*
X06043Y02255*
X06561Y02106D02*
Y02081D01*
X06566Y02076*
X06576*
X06581Y02081*
Y02106*
X06591Y02076D02*
X06601D01*
X06596*
Y02106*
X06591Y02101*
X05411Y03411D02*
X05406Y03416D01*
X05396*
X05391Y03411*
Y03406*
X05396Y03401*
X05406*
X05411Y03396*
Y03391*
X05406Y03387*
X05396*
X05391Y03391*
X05421Y03416D02*
Y03387D01*
X05431Y03396*
X05441Y03387*
Y03416*
X05451Y03387D02*
X05461D01*
X05456*
Y03416*
X05451Y03411*
X04951Y04322D02*
X04946Y04327D01*
X04936*
X04931Y04322*
Y04317*
X04936Y04312*
X04946*
X04951Y04307*
Y04302*
X04946Y04297*
X04936*
X04931Y04302*
X04981Y04327D02*
X04971Y04322D01*
X04961Y04312*
Y04302*
X04966Y04297*
X04976*
X04981Y04302*
Y04307*
X04976Y04312*
X04961*
X04426Y04322D02*
X04421Y04327D01*
X04411*
X04406Y04322*
Y04317*
X04411Y04312*
X04421*
X04426Y04307*
Y04302*
X04421Y04297*
X04411*
X04406Y04302*
X04456Y04327D02*
X04436D01*
Y04312*
X04446Y04317*
X04451*
X04456Y04312*
Y04302*
X04451Y04297*
X04441*
X04436Y04302*
X05101Y04094D02*
Y04124D01*
X05116*
X05121Y04119*
Y04109*
X05116Y04104*
X05101*
X05111D02*
X05121Y04094D01*
X05131Y04119D02*
X05136Y04124D01*
X05146*
X05151Y04119*
Y04114*
X05146Y04109*
X05141*
X05146*
X05151Y04104*
Y04099*
X05146Y04094*
X05136*
X05131Y04099*
X05181Y04124D02*
X05161D01*
Y04109*
X05171Y04114*
X05176*
X05181Y04109*
Y04099*
X05176Y04094*
X05166*
X05161Y04099*
X04644Y04058D02*
Y04088D01*
X04659*
X04664Y04083*
Y04073*
X04659Y04068*
X04644*
X04654D02*
X04664Y04058D01*
X04674Y04083D02*
X04679Y04088D01*
X04689*
X04694Y04083*
Y04078*
X04689Y04073*
X04684*
X04689*
X04694Y04068*
Y04063*
X04689Y04058*
X04679*
X04674Y04063*
X04719Y04058D02*
Y04088D01*
X04704Y04073*
X04724*
X05199Y04263D02*
Y04293D01*
X05214*
X05219Y04288*
Y04278*
X05214Y04273*
X05199*
X05209D02*
X05219Y04263D01*
X05229Y04288D02*
X05234Y04293D01*
X05244*
X05249Y04288*
Y04283*
X05244Y04278*
X05239*
X05244*
X05249Y04273*
Y04268*
X05244Y04263*
X05234*
X05229Y04268*
X05259Y04288D02*
X05264Y04293D01*
X05274*
X05279Y04288*
Y04283*
X05274Y04278*
X05269*
X05274*
X05279Y04273*
Y04268*
X05274Y04263*
X05264*
X05259Y04268*
X04639Y04263D02*
Y04293D01*
X04654*
X04659Y04288*
Y04278*
X04654Y04273*
X04639*
X04649D02*
X04659Y04263D01*
X04669Y04288D02*
X04674Y04293D01*
X04684*
X04689Y04288*
Y04283*
X04684Y04278*
X04679*
X04684*
X04689Y04273*
Y04268*
X04684Y04263*
X04674*
X04669Y04268*
X04719Y04263D02*
X04699D01*
X04719Y04283*
Y04288*
X04714Y04293*
X04704*
X04699Y04288*
X01198Y04013D02*
X01168D01*
Y04028*
X01173Y04033*
X01183*
X01188Y04028*
Y04013*
Y04023D02*
X01198Y04033D01*
X01173Y04043D02*
X01168Y04048D01*
Y04058*
X01173Y04063*
X01178*
X01183Y04058*
Y04053*
Y04058*
X01188Y04063*
X01193*
X01198Y04058*
Y04048*
X01193Y04043*
X01198Y04073D02*
Y04083D01*
Y04078*
X01168*
X01173Y04073*
X00993Y04004D02*
X00963D01*
Y04019*
X00968Y04024*
X00978*
X00983Y04019*
Y04004*
Y04014D02*
X00993Y04024D01*
X00968Y04034D02*
X00963Y04039D01*
Y04049*
X00968Y04054*
X00973*
X00978Y04049*
Y04044*
Y04049*
X00983Y04054*
X00988*
X00993Y04049*
Y04039*
X00988Y04034*
X00968Y04064D02*
X00963Y04069D01*
Y04079*
X00968Y04084*
X00988*
X00993Y04079*
Y04069*
X00988Y04064*
X00968*
X00789Y03998D02*
X00759D01*
Y04013*
X00764Y04018*
X00774*
X00779Y04013*
Y03998*
Y04008D02*
X00789Y04018D01*
Y04048D02*
Y04028D01*
X00769Y04048*
X00764*
X00759Y04043*
Y04033*
X00764Y04028*
X00784Y04058D02*
X00789Y04063D01*
Y04073*
X00784Y04078*
X00764*
X00759Y04073*
Y04063*
X00764Y04058*
X00769*
X00774Y04063*
Y04078*
X00588Y03998D02*
X00558D01*
Y04013*
X00563Y04018*
X00573*
X00578Y04013*
Y03998*
Y04008D02*
X00588Y04018D01*
Y04048D02*
Y04028D01*
X00568Y04048*
X00563*
X00558Y04043*
Y04033*
X00563Y04028*
Y04058D02*
X00558Y04063D01*
Y04073*
X00563Y04078*
X00568*
X00573Y04073*
X00578Y04078*
X00583*
X00588Y04073*
Y04063*
X00583Y04058*
X00578*
X00573Y04063*
X00568Y04058*
X00563*
X00573Y04063D02*
Y04073D01*
X04206Y03678D02*
Y03708D01*
X04221*
X04226Y03703*
Y03693*
X04221Y03688*
X04206*
X04216D02*
X04226Y03678D01*
X04256D02*
X04236D01*
X04256Y03698*
Y03703*
X04251Y03708*
X04241*
X04236Y03703*
X04266Y03708D02*
X04286D01*
Y03703*
X04266Y03683*
Y03678*
X03705Y03604D02*
X03675D01*
Y03619*
X0368Y03624*
X0369*
X03695Y03619*
Y03604*
Y03614D02*
X03705Y03624D01*
Y03654D02*
Y03634D01*
X03685Y03654*
X0368*
X03675Y03649*
Y03639*
X0368Y03634*
X03675Y03684D02*
X0368Y03674D01*
X0369Y03664*
X037*
X03705Y03669*
Y03679*
X037Y03684*
X03695*
X0369Y03679*
Y03664*
X03631Y0389D02*
Y0392D01*
X03646*
X03651Y03915*
Y03905*
X03646Y039*
X03631*
X03641D02*
X03651Y0389D01*
X03681D02*
X03661D01*
X03681Y0391*
Y03915*
X03676Y0392*
X03666*
X03661Y03915*
X03711Y0392D02*
X03691D01*
Y03905*
X03701Y0391*
X03706*
X03711Y03905*
Y03895*
X03706Y0389*
X03696*
X03691Y03895*
X03016Y00537D02*
X02986D01*
Y00552*
X02991Y00557*
X03001*
X03006Y00552*
Y00537*
Y00547D02*
X03016Y00557D01*
Y00587D02*
Y00567D01*
X02996Y00587*
X02991*
X02986Y00582*
Y00572*
X02991Y00567*
X03016Y00612D02*
X02986D01*
X03001Y00597*
Y00617*
X02468Y0054D02*
X02438D01*
Y00555*
X02443Y0056*
X02453*
X02458Y00555*
Y0054*
Y0055D02*
X02468Y0056D01*
Y0059D02*
Y0057D01*
X02448Y0059*
X02443*
X02438Y00585*
Y00575*
X02443Y0057*
Y006D02*
X02438Y00605D01*
Y00615*
X02443Y0062*
X02448*
X02453Y00615*
Y0061*
Y00615*
X02458Y0062*
X02463*
X02468Y00615*
Y00605*
X02463Y006*
X01982Y02632D02*
Y02662D01*
X01997*
X02002Y02657*
Y02647*
X01997Y02642*
X01982*
X01992D02*
X02002Y02632D01*
X02032D02*
X02012D01*
X02032Y02652*
Y02657*
X02027Y02662*
X02017*
X02012Y02657*
X02062Y02632D02*
X02042D01*
X02062Y02652*
Y02657*
X02057Y02662*
X02047*
X02042Y02657*
X03371Y03519D02*
X03341D01*
Y03534*
X03346Y03539*
X03356*
X03361Y03534*
Y03519*
Y03529D02*
X03371Y03539D01*
Y03569D02*
Y03549D01*
X03351Y03569*
X03346*
X03341Y03564*
Y03554*
X03346Y03549*
X03371Y03579D02*
Y03589D01*
Y03584*
X03341*
X03346Y03579*
X03168Y0351D02*
X03138D01*
Y03525*
X03143Y0353*
X03153*
X03158Y03525*
Y0351*
Y0352D02*
X03168Y0353D01*
Y0356D02*
Y0354D01*
X03148Y0356*
X03143*
X03138Y03555*
Y03545*
X03143Y0354*
Y0357D02*
X03138Y03575D01*
Y03585*
X03143Y0359*
X03163*
X03168Y03585*
Y03575*
X03163Y0357*
X03143*
X03066Y03513D02*
X03036D01*
Y03528*
X03041Y03533*
X03051*
X03056Y03528*
Y03513*
Y03523D02*
X03066Y03533D01*
Y03543D02*
Y03553D01*
Y03548*
X03036*
X03041Y03543*
X03061Y03568D02*
X03066Y03573D01*
Y03583*
X03061Y03588*
X03041*
X03036Y03583*
Y03573*
X03041Y03568*
X03046*
X03051Y03573*
Y03588*
X02972Y03513D02*
X02942D01*
Y03528*
X02947Y03533*
X02957*
X02962Y03528*
Y03513*
Y03523D02*
X02972Y03533D01*
Y03543D02*
Y03553D01*
Y03548*
X02942*
X02947Y03543*
Y03568D02*
X02942Y03573D01*
Y03583*
X02947Y03588*
X02952*
X02957Y03583*
X02962Y03588*
X02967*
X02972Y03583*
Y03573*
X02967Y03568*
X02962*
X02957Y03573*
X02952Y03568*
X02947*
X02957Y03573D02*
Y03583D01*
X06016Y02461D02*
X05986D01*
Y02476*
X05991Y02481*
X06001*
X06006Y02476*
Y02461*
Y02471D02*
X06016Y02481D01*
X06011Y02491D02*
X06016Y02496D01*
Y02506*
X06011Y02511*
X05991*
X05986Y02506*
Y02496*
X05991Y02491*
X05996*
X06001Y02496*
Y02511*
X07027Y01965D02*
X06997D01*
Y0198*
X07002Y01985*
X07012*
X07017Y0198*
Y01965*
Y01975D02*
X07027Y01985D01*
X07002Y01995D02*
X06997Y02D01*
Y0201*
X07002Y02015*
X07007*
X07012Y0201*
X07017Y02015*
X07022*
X07027Y0201*
Y02*
X07022Y01995*
X07017*
X07012Y02*
X07007Y01995*
X07002*
X07012Y02D02*
Y0201D01*
X06183Y0244D02*
Y0247D01*
X06198*
X06203Y02465*
Y02455*
X06198Y0245*
X06183*
X06193D02*
X06203Y0244D01*
X06213Y0247D02*
X06233D01*
Y02465*
X06213Y02445*
Y0244*
X06621Y01807D02*
Y01837D01*
X06636*
X06641Y01832*
Y01822*
X06636Y01817*
X06621*
X06631D02*
X06641Y01807D01*
X06671Y01837D02*
X06661Y01832D01*
X06651Y01822*
Y01812*
X06656Y01807*
X06666*
X06671Y01812*
Y01817*
X06666Y01822*
X06651*
X06845Y0175D02*
Y01779D01*
X0686*
X06865Y01774*
Y01764*
X0686Y0176*
X06845*
X06855D02*
X06865Y0175D01*
X0689D02*
Y01779D01*
X06875Y01764*
X06895*
X06209Y02058D02*
Y02088D01*
X06224*
X06229Y02083*
Y02073*
X06224Y02068*
X06209*
X06219D02*
X06229Y02058D01*
X06239Y02083D02*
X06244Y02088D01*
X06254*
X06259Y02083*
Y02078*
X06254Y02073*
X06249*
X06254*
X06259Y02068*
Y02063*
X06254Y02058*
X06244*
X06239Y02063*
X06766Y02174D02*
X06736D01*
Y02189*
X06741Y02194*
X06751*
X06756Y02189*
Y02174*
Y02184D02*
X06766Y02194D01*
Y02224D02*
Y02204D01*
X06746Y02224*
X06741*
X06736Y02219*
Y02209*
X06741Y02204*
X04137Y0366D02*
Y0369D01*
X04152*
X04157Y03685*
Y03675*
X04152Y0367*
X04137*
X04147D02*
X04157Y0366D01*
X04167D02*
X04177D01*
X04172*
Y0369*
X04167Y03685*
X01787Y00253D02*
Y00283D01*
X01802*
X01807Y00278*
Y00268*
X01802Y00263*
X01787*
X01837Y00253D02*
X01817D01*
X01837Y00273*
Y00278*
X01832Y00283*
X01822*
X01817Y00278*
X01556Y02619D02*
Y02649D01*
X01571*
X01576Y02644*
Y02634*
X01571Y02629*
X01556*
X01586Y02619D02*
X01596D01*
X01591*
Y02649*
X01586Y02644*
X06866Y02939D02*
Y02909D01*
X06886*
X06916D02*
X06896D01*
X06916Y02929*
Y02934*
X06911Y02939*
X06901*
X06896Y02934*
X05973Y01899D02*
Y01869D01*
X05993*
X06003D02*
X06013D01*
X06008*
Y01899*
X06003Y01894*
X04136Y04266D02*
X04126D01*
X04131*
Y04241*
X04126Y04236*
X04121*
X04116Y04241*
X04146Y04261D02*
X04151Y04266D01*
X04161*
X04166Y04261*
Y04256*
X04161Y04251*
X04156*
X04161*
X04166Y04246*
Y04241*
X04161Y04236*
X04151*
X04146Y04241*
X06951Y03499D02*
X06941D01*
X06946*
Y03474*
X06941Y03469*
X06936*
X06931Y03474*
X06981Y03469D02*
X06961D01*
X06981Y03489*
Y03494*
X06976Y03499*
X06966*
X06961Y03494*
X06351Y04188D02*
X06341D01*
X06346*
Y04163*
X06341Y04158*
X06336*
X06331Y04163*
X06361Y04158D02*
X06371D01*
X06366*
Y04188*
X06361Y04183*
X04144Y02907D02*
Y02887D01*
X04159*
Y02897*
Y02887*
X04174*
X04144Y02917D02*
X04174D01*
Y02932*
X04169Y02937*
X04164*
X04159Y02932*
Y02917*
Y02932*
X04154Y02937*
X04149*
X04144Y02932*
Y02917*
X04149Y02947D02*
X04144Y02952D01*
Y02962*
X04149Y02967*
X04154*
X04159Y02962*
Y02957*
Y02962*
X04164Y02967*
X04169*
X04174Y02962*
Y02952*
X04169Y02947*
X04496Y02854D02*
Y02834D01*
X04511*
Y02844*
Y02834*
X04526*
X04496Y02864D02*
X04526D01*
Y02879*
X04521Y02884*
X04516*
X04511Y02879*
Y02864*
Y02879*
X04506Y02884*
X04501*
X04496Y02879*
Y02864*
X04526Y02914D02*
Y02894D01*
X04506Y02914*
X04501*
X04496Y02909*
Y02899*
X04501Y02894*
X06141Y03434D02*
X06121D01*
Y03419*
X06131*
X06121*
Y03404*
X06151D02*
X06161D01*
X06156*
Y03434*
X06151Y03429*
X00881Y01101D02*
Y01071D01*
X00896*
X00901Y01076*
Y01096*
X00896Y01101*
X00881*
X00911Y01071D02*
X00921D01*
X00916*
Y01101*
X00911Y01096*
X00936D02*
X00941Y01101D01*
X00951*
X00956Y01096*
Y01091*
X00951Y01086*
X00956Y01081*
Y01076*
X00951Y01071*
X00941*
X00936Y01076*
Y01081*
X00941Y01086*
X00936Y01091*
Y01096*
X00941Y01086D02*
X00951D01*
X00881Y01626D02*
Y01596D01*
X00896*
X00901Y01601*
Y01621*
X00896Y01626*
X00881*
X00911Y01596D02*
X00921D01*
X00916*
Y01626*
X00911Y01621*
X00936Y01626D02*
X00956D01*
Y01621*
X00936Y01601*
Y01596*
X00881Y02676D02*
Y02646D01*
X00896*
X00901Y02651*
Y02671*
X00896Y02676*
X00881*
X00911Y02646D02*
X00921D01*
X00916*
Y02676*
X00911Y02671*
X00956Y02676D02*
X00946Y02671D01*
X00936Y02661*
Y02651*
X00941Y02646*
X00951*
X00956Y02651*
Y02656*
X00951Y02661*
X00936*
X00881Y02151D02*
Y02121D01*
X00896*
X00901Y02126*
Y02146*
X00896Y02151*
X00881*
X00911Y02121D02*
X00921D01*
X00916*
Y02151*
X00911Y02146*
X00956Y02151D02*
X00936D01*
Y02136*
X00946Y02141*
X00951*
X00956Y02136*
Y02126*
X00951Y02121*
X00941*
X00936Y02126*
X01162Y04167D02*
X01192D01*
Y04182*
X01187Y04187*
X01167*
X01162Y04182*
Y04167*
X01192Y04197D02*
Y04207D01*
Y04202*
X01162*
X01167Y04197*
X01192Y04237D02*
X01162D01*
X01177Y04222*
Y04242*
X0096Y04164D02*
X0099D01*
Y04179*
X00985Y04184*
X00965*
X0096Y04179*
Y04164*
X0099Y04194D02*
Y04204D01*
Y04199*
X0096*
X00965Y04194*
Y04219D02*
X0096Y04224D01*
Y04234*
X00965Y04239*
X0097*
X00975Y04234*
Y04229*
Y04234*
X0098Y04239*
X00985*
X0099Y04234*
Y04224*
X00985Y04219*
X00764Y04168D02*
X00794D01*
Y04183*
X00789Y04188*
X00769*
X00764Y04183*
Y04168*
X00794Y04198D02*
Y04208D01*
Y04203*
X00764*
X00769Y04198*
X00794Y04243D02*
Y04223D01*
X00774Y04243*
X00769*
X00764Y04238*
Y04228*
X00769Y04223*
X00561Y04178D02*
X00591D01*
Y04193*
X00586Y04198*
X00566*
X00561Y04193*
Y04178*
X00591Y04208D02*
Y04218D01*
Y04213*
X00561*
X00566Y04208*
X00591Y04233D02*
Y04243D01*
Y04238*
X00561*
X00566Y04233*
X03578Y03571D02*
X03608D01*
Y03586*
X03603Y03591*
X03583*
X03578Y03586*
Y03571*
X03608Y03601D02*
Y03611D01*
Y03606*
X03578*
X03583Y03601*
Y03626D02*
X03578Y03631D01*
Y03641*
X03583Y03646*
X03603*
X03608Y03641*
Y03631*
X03603Y03626*
X03583*
X0359Y03961D02*
X0362D01*
Y03976*
X03615Y03981*
X03595*
X0359Y03976*
Y03961*
X03615Y03991D02*
X0362Y03996D01*
Y04006*
X03615Y04011*
X03595*
X0359Y04006*
Y03996*
X03595Y03991*
X036*
X03605Y03996*
Y04011*
X03463Y03797D02*
X03493D01*
Y03812*
X03488Y03817*
X03468*
X03463Y03812*
Y03797*
X03468Y03827D02*
X03463Y03832D01*
Y03842*
X03468Y03847*
X03473*
X03478Y03842*
X03483Y03847*
X03488*
X03493Y03842*
Y03832*
X03488Y03827*
X03483*
X03478Y03832*
X03473Y03827*
X03468*
X03478Y03832D02*
Y03842D01*
X03235Y035D02*
X03265D01*
Y03515*
X0326Y0352*
X0324*
X03235Y03515*
Y035*
Y0353D02*
Y0355D01*
X0324*
X0326Y0353*
X03265*
X02705Y03852D02*
Y03822D01*
X0272*
X02725Y03827*
Y03847*
X0272Y03852*
X02705*
X02755D02*
X02745Y03847D01*
X02735Y03837*
Y03827*
X0274Y03822*
X0275*
X02755Y03827*
Y03832*
X0275Y03837*
X02735*
X02865Y03548D02*
X02895D01*
Y03563*
X0289Y03568*
X0287*
X02865Y03563*
Y03548*
Y03598D02*
Y03578D01*
X0288*
X02875Y03588*
Y03593*
X0288Y03598*
X0289*
X02895Y03593*
Y03583*
X0289Y03578*
X04324Y03663D02*
Y03633D01*
X04339*
X04344Y03638*
Y03658*
X04339Y03663*
X04324*
X04369Y03633D02*
Y03663D01*
X04354Y03648*
X04374*
X06341Y03788D02*
Y03758D01*
X06356*
X06361Y03763*
Y03783*
X06356Y03788*
X06341*
X06371Y03783D02*
X06376Y03788D01*
X06386*
X06391Y03783*
Y03778*
X06386Y03773*
X06381*
X06386*
X06391Y03768*
Y03763*
X06386Y03758*
X06376*
X06371Y03763*
X06206Y0348D02*
Y0345D01*
X06221*
X06226Y03455*
Y03475*
X06221Y0348*
X06206*
X06256Y0345D02*
X06236D01*
X06256Y0347*
Y03475*
X06251Y0348*
X06241*
X06236Y03475*
X06069Y03689D02*
Y03659D01*
X06084*
X06089Y03664*
Y03684*
X06084Y03689*
X06069*
X06099Y03659D02*
X06109D01*
X06104*
Y03689*
X06099Y03684*
X03685Y03415D02*
X0368Y0342D01*
X0367*
X03665Y03415*
Y03395*
X0367Y0339*
X0368*
X03685Y03395*
X03715Y0342D02*
X03705Y03415D01*
X03695Y03405*
Y03395*
X037Y0339*
X0371*
X03715Y03395*
Y034*
X0371Y03405*
X03695*
X03725Y0342D02*
X03745D01*
Y03415*
X03725Y03395*
Y0339*
X03806Y0331D02*
X03801Y03315D01*
X03791*
X03786Y0331*
Y0329*
X03791Y03285*
X03801*
X03806Y0329*
X03836Y03315D02*
X03826Y0331D01*
X03816Y033*
Y0329*
X03821Y03285*
X03831*
X03836Y0329*
Y03295*
X03831Y033*
X03816*
X03866Y03315D02*
X03856Y0331D01*
X03846Y033*
Y0329*
X03851Y03285*
X03861*
X03866Y0329*
Y03295*
X03861Y033*
X03846*
X03772Y03129D02*
X03767Y03134D01*
X03757*
X03752Y03129*
Y03109*
X03757Y03104*
X03767*
X03772Y03109*
X03802Y03134D02*
X03792Y03129D01*
X03782Y03119*
Y03109*
X03787Y03104*
X03797*
X03802Y03109*
Y03114*
X03797Y03119*
X03782*
X03832Y03134D02*
X03812D01*
Y03119*
X03822Y03124*
X03827*
X03832Y03119*
Y03109*
X03827Y03104*
X03817*
X03812Y03109*
X0378Y00638D02*
X03775Y00643D01*
X03765*
X0376Y00638*
Y00618*
X03765Y00613*
X03775*
X0378Y00618*
X0381Y00643D02*
X038Y00638D01*
X0379Y00628*
Y00618*
X03795Y00613*
X03805*
X0381Y00618*
Y00623*
X03805Y00628*
X0379*
X0382Y00638D02*
X03825Y00643D01*
X03835*
X0384Y00638*
Y00633*
X03835Y00628*
X0383*
X03835*
X0384Y00623*
Y00618*
X03835Y00613*
X03825*
X0382Y00618*
X03514Y00733D02*
X03509Y00738D01*
X03499*
X03494Y00733*
Y00713*
X03499Y00708*
X03509*
X03514Y00713*
X03544Y00738D02*
X03534Y00733D01*
X03524Y00723*
Y00713*
X03529Y00708*
X03539*
X03544Y00713*
Y00718*
X03539Y00723*
X03524*
X03574Y00708D02*
X03554D01*
X03574Y00728*
Y00733*
X03569Y00738*
X03559*
X03554Y00733*
X02772Y03462D02*
X02767Y03457D01*
Y03447*
X02772Y03442*
X02792*
X02797Y03447*
Y03457*
X02792Y03462*
X02767Y03492D02*
X02772Y03482D01*
X02782Y03472*
X02792*
X02797Y03477*
Y03487*
X02792Y03492*
X02787*
X02782Y03487*
Y03472*
X02797Y03502D02*
Y03512D01*
Y03507*
X02767*
X02772Y03502*
X02697Y03374D02*
X02692Y03369D01*
Y03359*
X02697Y03354*
X02717*
X02722Y03359*
Y03369*
X02717Y03374*
X02692Y03404D02*
X02697Y03394D01*
X02707Y03384*
X02717*
X02722Y03389*
Y03399*
X02717Y03404*
X02712*
X02707Y03399*
Y03384*
X02697Y03414D02*
X02692Y03419D01*
Y03429*
X02697Y03434*
X02717*
X02722Y03429*
Y03419*
X02717Y03414*
X02697*
X02071Y03636D02*
X02066Y03631D01*
Y03621*
X02071Y03616*
X02091*
X02096Y03621*
Y03631*
X02091Y03636*
X02066Y03666D02*
Y03646D01*
X02081*
X02076Y03656*
Y03661*
X02081Y03666*
X02091*
X02096Y03661*
Y03651*
X02091Y03646*
Y03676D02*
X02096Y03681D01*
Y03691*
X02091Y03696*
X02071*
X02066Y03691*
Y03681*
X02071Y03676*
X02076*
X02081Y03681*
Y03696*
X02207Y03783D02*
X02202Y03778D01*
Y03768*
X02207Y03763*
X02227*
X02232Y03768*
Y03778*
X02227Y03783*
X02202Y03813D02*
Y03793D01*
X02217*
X02212Y03803*
Y03808*
X02217Y03813*
X02227*
X02232Y03808*
Y03798*
X02227Y03793*
X02207Y03823D02*
X02202Y03828D01*
Y03838*
X02207Y03843*
X02212*
X02217Y03838*
X02222Y03843*
X02227*
X02232Y03838*
Y03828*
X02227Y03823*
X02222*
X02217Y03828*
X02212Y03823*
X02207*
X02217Y03828D02*
Y03838D01*
X06594Y02982D02*
X06589Y02987D01*
X06579*
X06574Y02982*
Y02962*
X06579Y02957*
X06589*
X06594Y02962*
X06624Y02987D02*
X06604D01*
Y02972*
X06614Y02977*
X06619*
X06624Y02972*
Y02962*
X06619Y02957*
X06609*
X06604Y02962*
X06634Y02987D02*
X06654D01*
Y02982*
X06634Y02962*
Y02957*
X06289Y03068D02*
X06284Y03073D01*
X06274*
X06269Y03068*
Y03048*
X06274Y03043*
X06284*
X06289Y03048*
X06319Y03073D02*
X06299D01*
Y03058*
X06309Y03063*
X06314*
X06319Y03058*
Y03048*
X06314Y03043*
X06304*
X06299Y03048*
X06349Y03073D02*
X06339Y03068D01*
X06329Y03058*
Y03048*
X06334Y03043*
X06344*
X06349Y03048*
Y03053*
X06344Y03058*
X06329*
X04273Y03825D02*
X04268Y0382D01*
Y0381*
X04273Y03805*
X04293*
X04298Y0381*
Y0382*
X04293Y03825*
X04268Y03855D02*
Y03835D01*
X04283*
X04278Y03845*
Y0385*
X04283Y03855*
X04293*
X04298Y0385*
Y0384*
X04293Y03835*
X04268Y03885D02*
Y03865D01*
X04283*
X04278Y03875*
Y0388*
X04283Y03885*
X04293*
X04298Y0388*
Y0387*
X04293Y03865*
X04132Y03908D02*
X04127Y03903D01*
Y03893*
X04132Y03888*
X04152*
X04157Y03893*
Y03903*
X04152Y03908*
X04127Y03938D02*
Y03918D01*
X04142*
X04137Y03928*
Y03933*
X04142Y03938*
X04152*
X04157Y03933*
Y03923*
X04152Y03918*
X04157Y03963D02*
X04127D01*
X04142Y03948*
Y03968*
X06051Y02439D02*
X06046Y02434D01*
Y02424*
X06051Y02419*
X06071*
X06076Y02424*
Y02434*
X06071Y02439*
X06076Y02469D02*
Y02449D01*
X06056Y02469*
X06051*
X06046Y02464*
Y02454*
X06051Y02449*
X06076Y02499D02*
Y02479D01*
X06056Y02499*
X06051*
X06046Y02494*
Y02484*
X06051Y02479*
X06101Y02113D02*
X06096Y02118D01*
X06086*
X06081Y02113*
Y02093*
X06086Y02088*
X06096*
X06101Y02093*
X06131Y02088D02*
X06111D01*
X06131Y02108*
Y02113*
X06126Y02118*
X06116*
X06111Y02113*
X06141Y02088D02*
X06151D01*
X06146*
Y02118*
X06141Y02113*
X06924Y01978D02*
X06919Y01973D01*
Y01963*
X06924Y01958*
X06944*
X06949Y01963*
Y01973*
X06944Y01978*
X06949Y02008D02*
Y01988D01*
X06929Y02008*
X06924*
X06919Y02003*
Y01993*
X06924Y01988*
Y02018D02*
X06919Y02023D01*
Y02033*
X06924Y02038*
X06944*
X06949Y02033*
Y02023*
X06944Y02018*
X06924*
X06853Y02169D02*
X06848Y02174D01*
X06838*
X06833Y02169*
Y02149*
X06838Y02144*
X06848*
X06853Y02149*
X06863Y02144D02*
X06873D01*
X06868*
Y02174*
X06863Y02169*
X06888Y02149D02*
X06893Y02144D01*
X06903*
X06908Y02149*
Y02169*
X06903Y02174*
X06893*
X06888Y02169*
Y02164*
X06893Y02159*
X06908*
X06727Y01758D02*
X06722Y01763D01*
X06712*
X06707Y01758*
Y01738*
X06712Y01733*
X06722*
X06727Y01738*
X06737Y01733D02*
X06747D01*
X06742*
Y01763*
X06737Y01758*
X06762D02*
X06767Y01763D01*
X06777*
X06782Y01758*
Y01753*
X06777Y01748*
X06782Y01743*
Y01738*
X06777Y01733*
X06767*
X06762Y01738*
Y01743*
X06767Y01748*
X06762Y01753*
Y01758*
X06767Y01748D02*
X06777D01*
X06728Y01693D02*
X06723Y01698D01*
X06713*
X06708Y01693*
Y01673*
X06713Y01668*
X06723*
X06728Y01673*
X06738Y01668D02*
X06748D01*
X06743*
Y01698*
X06738Y01693*
X06763Y01698D02*
X06783D01*
Y01693*
X06763Y01673*
Y01668*
X06727Y01628D02*
X06722Y01633D01*
X06712*
X06707Y01628*
Y01608*
X06712Y01603*
X06722*
X06727Y01608*
X06737Y01603D02*
X06747D01*
X06742*
Y01633*
X06737Y01628*
X06782Y01633D02*
X06772Y01628D01*
X06762Y01618*
Y01608*
X06767Y01603*
X06777*
X06782Y01608*
Y01613*
X06777Y01618*
X06762*
X06761Y01562D02*
X06756Y01567D01*
X06746*
X06741Y01562*
Y01542*
X06746Y01537*
X06756*
X06761Y01542*
X06771Y01537D02*
X06781D01*
X06776*
Y01567*
X06771Y01562*
X06816Y01567D02*
X06796D01*
Y01552*
X06806Y01557*
X06811*
X06816Y01552*
Y01542*
X06811Y01537*
X06801*
X06796Y01542*
X06762Y01496D02*
X06757Y01501D01*
X06747*
X06742Y01496*
Y01476*
X06747Y01471*
X06757*
X06762Y01476*
X06772Y01471D02*
X06782D01*
X06777*
Y01501*
X06772Y01496*
X06812Y01471D02*
Y01501D01*
X06797Y01486*
X06817*
X06761Y01422D02*
X06756Y01427D01*
X06746*
X06741Y01422*
Y01402*
X06746Y01397*
X06756*
X06761Y01402*
X06771Y01397D02*
X06781D01*
X06776*
Y01427*
X06771Y01422*
X06796D02*
X06801Y01427D01*
X06811*
X06816Y01422*
Y01417*
X06811Y01412*
X06806*
X06811*
X06816Y01407*
Y01402*
X06811Y01397*
X06801*
X06796Y01402*
X06199Y0265D02*
X06194Y02655D01*
X06184*
X06179Y0265*
Y0263*
X06184Y02625*
X06194*
X06199Y0263*
X06209Y02625D02*
X06219D01*
X06214*
Y02655*
X06209Y0265*
X06254Y02625D02*
X06234D01*
X06254Y02645*
Y0265*
X06249Y02655*
X06239*
X06234Y0265*
X06198Y02601D02*
X06193Y02606D01*
X06183*
X06178Y02601*
Y02581*
X06183Y02576*
X06193*
X06198Y02581*
X06208Y02576D02*
X06218D01*
X06213*
Y02606*
X06208Y02601*
X06233Y02576D02*
X06243D01*
X06238*
Y02606*
X06233Y02601*
X06197Y02552D02*
X06192Y02557D01*
X06182*
X06177Y02552*
Y02532*
X06182Y02527*
X06192*
X06197Y02532*
X06207Y02527D02*
X06217D01*
X06212*
Y02557*
X06207Y02552*
X06232D02*
X06237Y02557D01*
X06247*
X06252Y02552*
Y02532*
X06247Y02527*
X06237*
X06232Y02532*
Y02552*
X06199Y02702D02*
X06194Y02707D01*
X06184*
X06179Y02702*
Y02682*
X06184Y02677*
X06194*
X06199Y02682*
X06209D02*
X06214Y02677D01*
X06224*
X06229Y02682*
Y02702*
X06224Y02707*
X06214*
X06209Y02702*
Y02697*
X06214Y02692*
X06229*
X06312Y029D02*
X06307Y02895D01*
Y02885*
X06312Y0288*
X06332*
X06337Y02885*
Y02895*
X06332Y029*
X06312Y0291D02*
X06307Y02915D01*
Y02925*
X06312Y0293*
X06317*
X06322Y02925*
X06327Y0293*
X06332*
X06337Y02925*
Y02915*
X06332Y0291*
X06327*
X06322Y02915*
X06317Y0291*
X06312*
X06322Y02915D02*
Y02925D01*
X06179Y02903D02*
X06174Y02898D01*
Y02888*
X06179Y02883*
X06199*
X06204Y02888*
Y02898*
X06199Y02903*
X06174Y02913D02*
Y02933D01*
X06179*
X06199Y02913*
X06204*
X0665Y02231D02*
X06645Y02226D01*
Y02216*
X0665Y02211*
X0667*
X06675Y02216*
Y02226*
X0667Y02231*
X06645Y02261D02*
X0665Y02251D01*
X0666Y02241*
X0667*
X06675Y02246*
Y02256*
X0667Y02261*
X06665*
X0666Y02256*
Y02241*
X06326Y02057D02*
X06321Y02062D01*
X06311*
X06306Y02057*
Y02037*
X06311Y02032*
X06321*
X06326Y02037*
X06356Y02062D02*
X06336D01*
Y02047*
X06346Y02052*
X06351*
X06356Y02047*
Y02037*
X06351Y02032*
X06341*
X06336Y02037*
X06505Y02085D02*
X065Y0208D01*
Y0207*
X06505Y02065*
X06525*
X0653Y0207*
Y0208*
X06525Y02085*
X0653Y0211D02*
X065D01*
X06515Y02095*
Y02115*
X06461Y02166D02*
X06456Y02161D01*
Y02151*
X06461Y02146*
X06481*
X06486Y02151*
Y02161*
X06481Y02166*
X06461Y02176D02*
X06456Y02181D01*
Y02191*
X06461Y02196*
X06466*
X06471Y02191*
Y02186*
Y02191*
X06476Y02196*
X06481*
X06486Y02191*
Y02181*
X06481Y02176*
X05622Y03266D02*
X05617Y03271D01*
X05607*
X05602Y03266*
Y03246*
X05607Y03241*
X05617*
X05622Y03246*
X05652Y03241D02*
X05632D01*
X05652Y03261*
Y03266*
X05647Y03271*
X05637*
X05632Y03266*
X05764Y0327D02*
X05759Y03275D01*
X05749*
X05744Y0327*
Y0325*
X05749Y03245*
X05759*
X05764Y0325*
X05774Y03245D02*
X05784D01*
X05779*
Y03275*
X05774Y0327*
X00536Y01062D02*
Y01082D01*
X00546Y01092*
X00556Y01082*
Y01062*
Y01077*
X00536*
X00566Y01062D02*
Y01092D01*
X00586Y01062*
Y01092*
X00596Y01087D02*
X00601Y01092D01*
X00611*
X00616Y01087*
Y01082*
X00611Y01077*
X00616Y01072*
Y01067*
X00611Y01062*
X00601*
X00596Y01067*
Y01072*
X00601Y01077*
X00596Y01082*
Y01087*
X00601Y01077D02*
X00611D01*
X00536Y01587D02*
Y01607D01*
X00546Y01617*
X00556Y01607*
Y01587*
Y01602*
X00536*
X00566Y01587D02*
Y01617D01*
X00586Y01587*
Y01617*
X00596D02*
X00616D01*
Y01612*
X00596Y01592*
Y01587*
X00536Y02637D02*
Y02657D01*
X00546Y02667*
X00556Y02657*
Y02637*
Y02652*
X00536*
X00566Y02637D02*
Y02667D01*
X00586Y02637*
Y02667*
X00616D02*
X00606Y02662D01*
X00596Y02652*
Y02642*
X00601Y02637*
X00611*
X00616Y02642*
Y02647*
X00611Y02652*
X00596*
X00536Y02112D02*
Y02132D01*
X00546Y02142*
X00556Y02132*
Y02112*
Y02127*
X00536*
X00566Y02112D02*
Y02142D01*
X00586Y02112*
Y02142*
X00616D02*
X00596D01*
Y02127*
X00606Y02132*
X00611*
X00616Y02127*
Y02117*
X00611Y02112*
X00601*
X00596Y02117*
X00404Y00728D02*
Y00748D01*
X00414Y00758*
X00424Y00748*
Y00728*
Y00743*
X00404*
X00434Y00728D02*
Y00758D01*
X00454Y00728*
Y00758*
X00479Y00728D02*
Y00758D01*
X00464Y00743*
X00484*
X00406Y01252D02*
Y01272D01*
X00416Y01282*
X00426Y01272*
Y01252*
Y01267*
X00406*
X00436Y01252D02*
Y01282D01*
X00456Y01252*
Y01282*
X00466Y01277D02*
X00471Y01282D01*
X00481*
X00486Y01277*
Y01272*
X00481Y01267*
X00476*
X00481*
X00486Y01262*
Y01257*
X00481Y01252*
X00471*
X00466Y01257*
X00404Y01775D02*
Y01795D01*
X00414Y01805*
X00424Y01795*
Y01775*
Y0179*
X00404*
X00434Y01775D02*
Y01805D01*
X00454Y01775*
Y01805*
X00484Y01775D02*
X00464D01*
X00484Y01795*
Y018*
X00479Y01805*
X00469*
X00464Y018*
X00406Y02301D02*
Y02321D01*
X00416Y02331*
X00426Y02321*
Y02301*
Y02316*
X00406*
X00436Y02301D02*
Y02331D01*
X00456Y02301*
Y02331*
X00466Y02301D02*
X00476D01*
X00471*
Y02331*
X00466Y02326*
G54D25*
X06557Y03151D03*
M02*